G04 ================== begin FILE IDENTIFICATION RECORD ==================*
G04 Layout Name:  15105-sa.brd*
G04 Film Name:    L4VCC*
G04 File Format:  Gerber RS274X*
G04 File Origin:  Cadence Allegro 16.5-S056*
G04 Origin Date:  Wed Nov 16 02:02:19 2016*
G04 *
G04 Layer:  VIA CLASS/L4VCC*
G04 Layer:  PIN/L4VCC*
G04 Layer:  PACKAGE GEOMETRY/PWRVCC*
G04 Layer:  ETCH/L4VCC*
G04 Layer:  DRAWING FORMAT/LAYER_PCB_STORY*
G04 Layer:  DRAWING FORMAT/LAYER_L4VCC*
G04 *
G04 Offset:    (0.00 0.00)*
G04 Mirror:    No*
G04 Mode:      Negative*
G04 Rotation:  0*
G04 FullContactRelief:  No*
G04 UndefLineWidth:     6.00*
G04 ================== end FILE IDENTIFICATION RECORD ====================*
%FSLAX35Y35*MOIN*%
%IR0*IPPOS*OFA0.00000B0.00000*MIA0B0*SFA1.00000B1.00000*%
%AMMACRO38*
4,1,13,.02632,.01218,
.028035,.007425,
.028899,.002443,
.028884,-.002612,
.027991,-.007588,
.02632,-.01218,
.03005,-.01591,
.032356,-.01045,
.033679,-.004673,
.033979,.001247,
.033246,.007128,
.031504,.012793,
.03005,.01591,
.02632,.01218,
0.0*
4,1,13,.01218,-.02632,
.007425,-.028035,
.002443,-.028899,
-.002612,-.028884,
-.007588,-.027991,
-.01218,-.02632,
-.01591,-.03005,
-.01045,-.032356,
-.004673,-.033679,
.001247,-.033979,
.007128,-.033246,
.012793,-.031504,
.01591,-.03005,
.01218,-.02632,
0.0*
4,1,13,-.02632,-.01218,
-.028035,-.007425,
-.028899,-.002443,
-.028884,.002612,
-.027991,.007588,
-.02632,.01218,
-.03005,.01591,
-.032356,.01045,
-.033679,.004673,
-.033979,-.001247,
-.033246,-.007128,
-.031504,-.012793,
-.03005,-.01591,
-.02632,-.01218,
0.0*
4,1,13,-.01218,.02632,
-.007425,.028035,
-.002443,.028899,
.002612,.028884,
.007588,.027991,
.01218,.02632,
.01591,.03005,
.01045,.032356,
.004673,.033679,
-.001247,.033979,
-.007128,.033246,
-.012793,.031504,
-.01591,.03005,
-.01218,.02632,
0.0*
%
%ADD38MACRO38*%
%ADD14C,.03*%
%ADD24C,.032*%
%ADD34C,.051*%
%ADD21C,.06*%
%ADD36C,.043*%
%ADD32C,.07*%
%ADD37C,.063*%
%ADD28C,.036*%
%ADD13C,.09*%
%ADD25C,.028*%
%ADD18C,.064*%
%ADD23C,.066*%
%ADD31C,.058*%
%ADD29C,.068*%
%ADD12C,.078*%
%AMMACRO26*
4,1,15,.00398,.00044,
.003999,.000208,
.004004,-.000025,
.003996,-.000258,
.00398,-.00044,
.00483,-.00129,
.004897,-.001007,
.004947,-.000721,
.004981,-.000432,
.004997,-.000141,
.004997,.000149,
.00498,.00044,
.004946,.000729,
.004895,.001015,
.00483,.00129,
.00398,.00044,
90.*
4,1,15,.00044,-.00398,
.000208,-.003999,
-.000025,-.004004,
-.000258,-.003996,
-.00044,-.00398,
-.00129,-.00483,
-.001007,-.004897,
-.000721,-.004947,
-.000432,-.004981,
-.000141,-.004997,
.000149,-.004997,
.00044,-.00498,
.000729,-.004946,
.001015,-.004895,
.00129,-.00483,
.00044,-.00398,
90.*
4,1,15,-.00398,-.00044,
-.003999,-.000208,
-.004004,.000025,
-.003996,.000258,
-.00398,.00044,
-.00483,.00129,
-.004897,.001007,
-.004947,.000721,
-.004981,.000432,
-.004997,.000141,
-.004997,-.000149,
-.00498,-.00044,
-.004946,-.000729,
-.004895,-.001015,
-.00483,-.00129,
-.00398,-.00044,
90.*
4,1,15,-.00044,.00398,
-.000208,.003999,
.000025,.004004,
.000258,.003996,
.00044,.00398,
.00129,.00483,
.001007,.004897,
.000721,.004947,
.000432,.004981,
.000141,.004997,
-.000149,.004997,
-.00044,.00498,
-.000729,.004946,
-.001015,.004895,
-.00129,.00483,
-.00044,.00398,
90.*
%
%ADD26MACRO26*%
%AMMACRO11*
4,1,15,.00398,.00044,
.003999,.000208,
.004004,-.000025,
.003996,-.000258,
.00398,-.00044,
.00483,-.00129,
.004897,-.001007,
.004947,-.000721,
.004981,-.000432,
.004997,-.000141,
.004997,.000149,
.00498,.00044,
.004946,.000729,
.004895,.001015,
.00483,.00129,
.00398,.00044,
0.0*
4,1,15,.00044,-.00398,
.000208,-.003999,
-.000025,-.004004,
-.000258,-.003996,
-.00044,-.00398,
-.00129,-.00483,
-.001007,-.004897,
-.000721,-.004947,
-.000432,-.004981,
-.000141,-.004997,
.000149,-.004997,
.00044,-.00498,
.000729,-.004946,
.001015,-.004895,
.00129,-.00483,
.00044,-.00398,
0.0*
4,1,15,-.00398,-.00044,
-.003999,-.000208,
-.004004,.000025,
-.003996,.000258,
-.00398,.00044,
-.00483,.00129,
-.004897,.001007,
-.004947,.000721,
-.004981,.000432,
-.004997,.000141,
-.004997,-.000149,
-.00498,-.00044,
-.004946,-.000729,
-.004895,-.001015,
-.00483,-.00129,
-.00398,-.00044,
0.0*
4,1,15,-.00044,.00398,
-.000208,.003999,
.000025,.004004,
.000258,.003996,
.00044,.00398,
.00129,.00483,
.001007,.004897,
.000721,.004947,
.000432,.004981,
.000141,.004997,
-.000149,.004997,
-.00044,.00498,
-.000729,.004946,
-.001015,.004895,
-.00129,.00483,
-.00044,.00398,
0.0*
%
%ADD11MACRO11*%
%AMMACRO33*
4,1,13,.02632,.01218,
.028035,.007425,
.028899,.002443,
.028884,-.002612,
.027991,-.007588,
.02632,-.01218,
.03005,-.01591,
.032356,-.01045,
.033679,-.004673,
.033979,.001247,
.033246,.007128,
.031504,.012793,
.03005,.01591,
.02632,.01218,
180.*
4,1,13,.01218,-.02632,
.007425,-.028035,
.002443,-.028899,
-.002612,-.028884,
-.007588,-.027991,
-.01218,-.02632,
-.01591,-.03005,
-.01045,-.032356,
-.004673,-.033679,
.001247,-.033979,
.007128,-.033246,
.012793,-.031504,
.01591,-.03005,
.01218,-.02632,
180.*
4,1,13,-.02632,-.01218,
-.028035,-.007425,
-.028899,-.002443,
-.028884,.002612,
-.027991,.007588,
-.02632,.01218,
-.03005,.01591,
-.032356,.01045,
-.033679,.004673,
-.033979,-.001247,
-.033246,-.007128,
-.031504,-.012793,
-.03005,-.01591,
-.02632,-.01218,
180.*
4,1,13,-.01218,.02632,
-.007425,.028035,
-.002443,.028899,
.002612,.028884,
.007588,.027991,
.01218,.02632,
.01591,.03005,
.01045,.032356,
.004673,.033679,
-.001247,.033979,
-.007128,.033246,
-.012793,.031504,
-.01591,.03005,
-.01218,.02632,
180.*
%
%ADD33MACRO33*%
%ADD10C,.114*%
%ADD19C,.208*%
%ADD16C,.19*%
%ADD22C,.119*%
%ADD17C,.156*%
%ADD30C,.166*%
%AMMACRO20*
4,1,15,.00398,.00044,
.003999,.000208,
.004004,-.000025,
.003996,-.000258,
.00398,-.00044,
.00483,-.00129,
.004897,-.001007,
.004947,-.000721,
.004981,-.000432,
.004997,-.000141,
.004997,.000149,
.00498,.00044,
.004946,.000729,
.004895,.001015,
.00483,.00129,
.00398,.00044,
180.*
4,1,15,.00044,-.00398,
.000208,-.003999,
-.000025,-.004004,
-.000258,-.003996,
-.00044,-.00398,
-.00129,-.00483,
-.001007,-.004897,
-.000721,-.004947,
-.000432,-.004981,
-.000141,-.004997,
.000149,-.004997,
.00044,-.00498,
.000729,-.004946,
.001015,-.004895,
.00129,-.00483,
.00044,-.00398,
180.*
4,1,15,-.00398,-.00044,
-.003999,-.000208,
-.004004,.000025,
-.003996,.000258,
-.00398,.00044,
-.00483,.00129,
-.004897,.001007,
-.004947,.000721,
-.004981,.000432,
-.004997,.000141,
-.004997,-.000149,
-.00498,-.00044,
-.004946,-.000729,
-.004895,-.001015,
-.00483,-.00129,
-.00398,-.00044,
180.*
4,1,15,-.00044,.00398,
-.000208,.003999,
.000025,.004004,
.000258,.003996,
.00044,.00398,
.00129,.00483,
.001007,.004897,
.000721,.004947,
.000432,.004981,
.000141,.004997,
-.000149,.004997,
-.00044,.00498,
-.000729,.004946,
-.001015,.004895,
-.00129,.00483,
-.00044,.00398,
180.*
%
%ADD20MACRO20*%
%AMMACRO15*
4,1,15,.00398,.00044,
.003999,.000208,
.004004,-.000025,
.003996,-.000258,
.00398,-.00044,
.00483,-.00129,
.004897,-.001007,
.004947,-.000721,
.004981,-.000432,
.004997,-.000141,
.004997,.000149,
.00498,.00044,
.004946,.000729,
.004895,.001015,
.00483,.00129,
.00398,.00044,
270.*
4,1,15,.00044,-.00398,
.000208,-.003999,
-.000025,-.004004,
-.000258,-.003996,
-.00044,-.00398,
-.00129,-.00483,
-.001007,-.004897,
-.000721,-.004947,
-.000432,-.004981,
-.000141,-.004997,
.000149,-.004997,
.00044,-.00498,
.000729,-.004946,
.001015,-.004895,
.00129,-.00483,
.00044,-.00398,
270.*
4,1,15,-.00398,-.00044,
-.003999,-.000208,
-.004004,.000025,
-.003996,.000258,
-.00398,.00044,
-.00483,.00129,
-.004897,.001007,
-.004947,.000721,
-.004981,.000432,
-.004997,.000141,
-.004997,-.000149,
-.00498,-.00044,
-.004946,-.000729,
-.004895,-.001015,
-.00483,-.00129,
-.00398,-.00044,
270.*
4,1,15,-.00044,.00398,
-.000208,.003999,
.000025,.004004,
.000258,.003996,
.00044,.00398,
.00129,.00483,
.001007,.004897,
.000721,.004947,
.000432,.004981,
.000141,.004997,
-.000149,.004997,
-.00044,.00498,
-.000729,.004946,
-.001015,.004895,
-.00129,.00483,
-.00044,.00398,
270.*
%
%ADD15MACRO15*%
%AMMACRO35*
4,1,14,.05302,.02473,
.056509,.015147,
.058281,.005105,
.058282,-.005093,
.056512,-.015136,
.053025,-.02472,
.05302,-.02473,
.05676,-.02847,
.060841,-.018181,
.063074,-.00734,
.063391,.003724,
.061781,.014675,
.058294,.025181,
.05676,.02847,
.05302,.02473,
0.0*
4,1,14,.02473,-.05302,
.015147,-.056509,
.005105,-.058281,
-.005093,-.058282,
-.015136,-.056512,
-.02472,-.053025,
-.02473,-.05302,
-.02847,-.05676,
-.018181,-.060841,
-.00734,-.063074,
.003724,-.063391,
.014675,-.061781,
.025181,-.058294,
.02847,-.05676,
.02473,-.05302,
0.0*
4,1,14,-.05302,-.02473,
-.056509,-.015147,
-.058281,-.005105,
-.058282,.005093,
-.056512,.015136,
-.053025,.02472,
-.05302,.02473,
-.05676,.02847,
-.060841,.018181,
-.063074,.00734,
-.063391,-.003724,
-.061781,-.014675,
-.058294,-.025181,
-.05676,-.02847,
-.05302,-.02473,
0.0*
4,1,14,-.02473,.05302,
-.015147,.056509,
-.005105,.058281,
.005093,.058282,
.015136,.056512,
.02472,.053025,
.02473,.05302,
.02847,.05676,
.018181,.060841,
.00734,.063074,
-.003724,.063391,
-.014675,.061781,
-.025181,.058294,
-.02847,.05676,
-.02473,.05302,
0.0*
%
%ADD35MACRO35*%
%AMMACRO27*
4,1,13,.02556,.01142,
.027155,.006808,
.027924,.001989,
.027846,-.00289,
.026921,-.007681,
.02556,-.01142,
.02931,-.01517,
.031499,-.00985,
.032731,-.004231,
.032968,.001517,
.032204,.007219,
.030461,.012702,
.02931,.01517,
.02556,.01142,
0.0*
4,1,13,.01142,-.02556,
.006808,-.027155,
.001989,-.027924,
-.00289,-.027846,
-.007681,-.026921,
-.01142,-.02556,
-.01517,-.02931,
-.00985,-.031499,
-.004231,-.032731,
.001517,-.032968,
.007219,-.032204,
.012702,-.030461,
.01517,-.02931,
.01142,-.02556,
0.0*
4,1,13,-.02556,-.01142,
-.027155,-.006808,
-.027924,-.001989,
-.027846,.00289,
-.026921,.007681,
-.02556,.01142,
-.02931,.01517,
-.031499,.00985,
-.032731,.004231,
-.032968,-.001517,
-.032204,-.007219,
-.030461,-.012702,
-.02931,-.01517,
-.02556,-.01142,
0.0*
4,1,13,-.01142,.02556,
-.006808,.027155,
-.001989,.027924,
.00289,.027846,
.007681,.026921,
.01142,.02556,
.01517,.02931,
.00985,.031499,
.004231,.032731,
-.001517,.032968,
-.007219,.032204,
-.012702,.030461,
-.01517,.02931,
-.01142,.02556,
0.0*
%
%ADD27MACRO27*%
%ADD39C,.02*%
%ADD40C,.006*%
%ADD50C,.08024*%
%ADD49C,.06404*%
%ADD51C,.05604*%
%ADD48C,.08224*%
%ADD41C,.11004*%
%ADD42C,.10224*%
%ADD46C,.3151*%
%ADD44C,.15204*%
%ADD43C,.31404*%
%ADD45C,.31532*%
%ADD52C,.31506*%
%ADD47C,.31534*%
%ADD54O,.09222X.04822*%
%ADD53O,.09224X.04824*%
%ADD55C,.31498*%
G75*
%LPD*%
G75*
G36*
G01X-6000Y-25685D02*
X1406000D01*
Y903637D01*
X-6000D01*
Y-25685D01*
G37*
%LPC*%
G75*
G36*
G01X3937Y837547D02*
X97500D01*
Y822672D01*
X100172Y820000D01*
X126328D01*
X132500Y826172D01*
Y836672D01*
X136500Y840672D01*
Y883398D01*
X288732D01*
Y876377D01*
G03X288826Y875176I7725J0D01*
G03X295420Y868723I7631J1202D01*
G03X297493I1037J7261D01*
G03X304181Y876378I-1037J7655D01*
G01Y883398D01*
X439909D01*
Y875590D01*
G03X444881Y870618I4973J1D01*
G01X446996D01*
Y845669D01*
G03X455118Y837547I8122J0D01*
G01X517323D01*
G03X525445Y845669I0J8122D01*
G01Y870618D01*
X527560D01*
G03X532532Y875590I-1J4973D01*
G01Y883398D01*
X706055D01*
Y876377D01*
G03X706149Y875176I7725J0D01*
G03X712743Y868723I7631J1202D01*
G03X714816I1037J7261D01*
G03X721504Y876378I-1037J7655D01*
G01Y883398D01*
X857232D01*
Y875590D01*
G03X862204Y870618I4973J1D01*
G01X864319D01*
Y845669D01*
G03X872441Y837547I8122J0D01*
G01X902134D01*
G02X918815Y820866I0J-16681D01*
G01Y650669D01*
G03X926819Y642665I8004J0D01*
G01X983748D01*
G03X991752Y650669I0J8004D01*
G01Y820866D01*
G02X1008433Y837547I16681J0D01*
G01X1013386D01*
G03X1021508Y845669I0J8122D01*
G01Y870618D01*
X1023623D01*
G03X1028595Y875590I-1J4973D01*
G01Y883398D01*
X1202118D01*
Y876377D01*
G03X1202212Y875176I7725J0D01*
G03X1208806Y868723I7631J1202D01*
G03X1210879I1036J7261D01*
G03X1217567Y876378I-1037J7655D01*
G01Y883398D01*
X1353295D01*
Y875590D01*
G03X1358267Y870618I4973J1D01*
G01X1360382D01*
Y845669D01*
G03X1368504Y837547I8122J0D01*
G01X1396063D01*
G02X1396996Y836614I0J-933D01*
G01Y76626D01*
X1396653D01*
G03X1391681Y71654I0J-4972D01*
G01Y40157D01*
G03X1396653Y35185I4972J0D01*
G01X1396996D01*
Y3937D01*
G02X1396063Y3004I-933J0D01*
G01X1310039D01*
G03X1303098Y-3937I0J-6941D01*
G01Y-15748D01*
G02X1302165Y-16681I-933J0D01*
G01X486762D01*
G02X481892Y-11811I0J4870D01*
G01Y-7874D01*
G03X471014Y3004I-10878J0D01*
G01X212402D01*
G02X207532Y7874I0J4870D01*
G01Y94528D01*
G03X196654Y105406I-10878J0D01*
G01X7874D01*
G02X3004Y110276I0J4870D01*
G01Y836614D01*
G02X3937Y837547I933J0D01*
G37*
G36*
G01X101828Y824000D02*
X101500Y824328D01*
Y837685D01*
X101659Y837719D01*
G03X108122Y845669I-1658J7950D01*
G01Y870618D01*
X110237D01*
G03X115209Y875590I-1J4973D01*
G01Y883398D01*
X132500D01*
Y842328D01*
X128500Y838328D01*
Y827828D01*
X124672Y824000D01*
X101828D01*
G37*
%LPD*%
G75*
G36*
G01X621794Y85929D02*
X621802Y85934D01*
X624757Y80419D01*
X624754Y80416D01*
X624751Y80414D01*
X624779Y80355D01*
G02X620463Y77990I-2202J-1102D01*
G01X620402Y78084D01*
X620399Y78082D01*
X617444Y83599D01*
X617447Y83601D01*
X617407Y83691D01*
G02X621794Y85929I2217J1073D01*
G37*
G36*
G01X542707Y77990D02*
X542646Y78084D01*
X542643Y78082D01*
X539688Y83597D01*
X539691Y83600D01*
X539694Y83602D01*
X539666Y83661D01*
G02X544038Y85929I2202J1103D01*
G01X544046Y85934D01*
X547001Y80417D01*
X546998Y80415D01*
X547038Y80325D01*
G02X542707Y77990I-2217J-1072D01*
G37*
G36*
G01X1343726Y873166D02*
X1340525D01*
G02X1340526Y877186I1J2010D01*
G01X1343726D01*
G02Y873166I0J-2010D01*
G37*
G36*
G01X1331128D02*
X1327928D01*
G02Y877186I0J2010D01*
G01X1331129D01*
G02X1331128Y873166I-1J-2010D01*
G37*
G36*
G01X1318529D02*
X1315329D01*
G02Y877186I0J2010D01*
G01X1318530D01*
G02X1318529Y873166I-1J-2010D01*
G37*
G36*
G01X1305931D02*
X1302731D01*
G02Y877186I0J2010D01*
G01X1305932D01*
G02X1305931Y873166I-1J-2010D01*
G37*
G36*
G01X1293333D02*
X1290133D01*
G02Y877186I0J2010D01*
G01X1293334D01*
G02X1293333Y873166I-1J-2010D01*
G37*
G36*
G01X1280734D02*
X1277534D01*
G02Y877186I0J2010D01*
G01X1280735D01*
G02X1280734Y873166I-1J-2010D01*
G37*
G36*
G01X1268136D02*
X1264936D01*
G02Y877186I0J2010D01*
G01X1268137D01*
G02X1268136Y873166I-1J-2010D01*
G37*
G36*
G01X1255537D02*
X1252337D01*
G02Y877186I0J2010D01*
G01X1255538D01*
G02X1255537Y873166I-1J-2010D01*
G37*
G36*
G01X1242939D02*
X1239739D01*
G02Y877186I0J2010D01*
G01X1242940D01*
G02X1242939Y873166I-1J-2010D01*
G37*
G36*
G01X1230340D02*
X1227140D01*
G02Y877186I0J2010D01*
G01X1230341D01*
G02X1230340Y873166I-1J-2010D01*
G37*
G36*
G01X1186246D02*
X1183046D01*
G02Y877186I0J2010D01*
G01X1186247D01*
G02X1186246Y873166I-1J-2010D01*
G37*
G36*
G01X1164199D02*
X1160999D01*
G02Y877186I0J2010D01*
G01X1164200D01*
G02X1164199Y873166I-1J-2010D01*
G37*
G36*
G01X1151600D02*
X1148400D01*
G02Y877186I0J2010D01*
G01X1151601D01*
G02X1151600Y873166I-1J-2010D01*
G37*
G36*
G01X1139002D02*
X1135802D01*
G02Y877186I0J2010D01*
G01X1139003D01*
G02X1139002Y873166I-1J-2010D01*
G37*
G36*
G01X1126403D02*
X1123203D01*
G02Y877186I0J2010D01*
G01X1126404D01*
G02X1126403Y873166I-1J-2010D01*
G37*
G36*
G01X1113805D02*
X1110605D01*
G02Y877186I0J2010D01*
G01X1113806D01*
G02X1113805Y873166I-1J-2010D01*
G37*
G36*
G01X1101207D02*
X1098007D01*
G02Y877186I0J2010D01*
G01X1101208D01*
G02X1101207Y873166I-1J-2010D01*
G37*
G36*
G01X1088608D02*
X1085408D01*
G02Y877186I0J2010D01*
G01X1088609D01*
G02X1088608Y873166I-1J-2010D01*
G37*
G36*
G01X1076010D02*
X1072810D01*
G02Y877186I0J2010D01*
G01X1076011D01*
G02X1076010Y873166I-1J-2010D01*
G37*
G36*
G01X1050813D02*
X1047613D01*
G02Y877186I0J2010D01*
G01X1050814D01*
G02X1050813Y873166I-1J-2010D01*
G37*
G36*
G01X1038214D02*
X1035014D01*
G02Y877186I0J2010D01*
G01X1038215D01*
G02X1038214Y873166I-1J-2010D01*
G37*
G36*
G01X847663D02*
X844463D01*
G02Y877186I0J2010D01*
G01X847664D01*
G02X847663Y873166I-1J-2010D01*
G37*
G36*
G01X835065D02*
X831865D01*
G02Y877186I0J2010D01*
G01X835066D01*
G02X835065Y873166I-1J-2010D01*
G37*
G36*
G01X809868D02*
X806668D01*
G02Y877186I0J2010D01*
G01X809869D01*
G02X809868Y873166I-1J-2010D01*
G37*
G36*
G01X797270D02*
X794070D01*
G02Y877186I0J2010D01*
G01X797271D01*
G02X797270Y873166I-1J-2010D01*
G37*
G36*
G01X784671D02*
X781471D01*
G02Y877186I0J2010D01*
G01X784672D01*
G02X784671Y873166I-1J-2010D01*
G37*
G36*
G01X772073D02*
X768873D01*
G02Y877186I0J2010D01*
G01X772074D01*
G02X772073Y873166I-1J-2010D01*
G37*
G36*
G01X759474D02*
X756274D01*
G02Y877186I0J2010D01*
G01X759475D01*
G02X759474Y873166I-1J-2010D01*
G37*
G36*
G01X746876D02*
X743676D01*
G02Y877186I0J2010D01*
G01X746877D01*
G02X746876Y873166I-1J-2010D01*
G37*
G36*
G01X734277D02*
X731076D01*
G02X731077Y877186I1J2010D01*
G01X734277D01*
G02Y873166I0J-2010D01*
G37*
G36*
G01X690183D02*
X686983D01*
G02Y877186I0J2010D01*
G01X690184D01*
G02X690183Y873166I-1J-2010D01*
G37*
G36*
G01X677585D02*
X674385D01*
G02Y877186I0J2010D01*
G01X677586D01*
G02X677585Y873166I-1J-2010D01*
G37*
G36*
G01X664986D02*
X661786D01*
G02Y877186I0J2010D01*
G01X664987D01*
G02X664986Y873166I-1J-2010D01*
G37*
G36*
G01X652388D02*
X649188D01*
G02Y877186I0J2010D01*
G01X652389D01*
G02X652388Y873166I-1J-2010D01*
G37*
G36*
G01X630340D02*
X627140D01*
G02Y877186I0J2010D01*
G01X630341D01*
G02X630340Y873166I-1J-2010D01*
G37*
G36*
G01X617742D02*
X614542D01*
G02Y877186I0J2010D01*
G01X617743D01*
G02X617742Y873166I-1J-2010D01*
G37*
G36*
G01X605144D02*
X601944D01*
G02Y877186I0J2010D01*
G01X605145D01*
G02X605144Y873166I-1J-2010D01*
G37*
G36*
G01X592545D02*
X589345D01*
G02Y877186I0J2010D01*
G01X592546D01*
G02X592545Y873166I-1J-2010D01*
G37*
G36*
G01X579947D02*
X576747D01*
G02Y877186I0J2010D01*
G01X579948D01*
G02X579947Y873166I-1J-2010D01*
G37*
G36*
G01X567348D02*
X564148D01*
G02Y877186I0J2010D01*
G01X567349D01*
G02X567348Y873166I-1J-2010D01*
G37*
G36*
G01X554750D02*
X551550D01*
G02Y877186I0J2010D01*
G01X554751D01*
G02X554750Y873166I-1J-2010D01*
G37*
G36*
G01X542151D02*
X538951D01*
G02Y877186I0J2010D01*
G01X542152D01*
G02X542151Y873166I-1J-2010D01*
G37*
G36*
G01X420891D02*
X417691D01*
G02Y877186I0J2010D01*
G01X420892D01*
G02X420891Y873166I-1J-2010D01*
G37*
G36*
G01X408292D02*
X405092D01*
G02Y877186I0J2010D01*
G01X408293D01*
G02X408292Y873166I-1J-2010D01*
G37*
G36*
G01X395694D02*
X392494D01*
G02Y877186I0J2010D01*
G01X395695D01*
G02X395694Y873166I-1J-2010D01*
G37*
G36*
G01X383096D02*
X379896D01*
G02Y877186I0J2010D01*
G01X383097D01*
G02X383096Y873166I-1J-2010D01*
G37*
G36*
G01X361048D02*
X357848D01*
G02Y877186I0J2010D01*
G01X361049D01*
G02X361048Y873166I-1J-2010D01*
G37*
G36*
G01X348450D02*
X345250D01*
G02Y877186I0J2010D01*
G01X348451D01*
G02X348450Y873166I-1J-2010D01*
G37*
G36*
G01X335851D02*
X332651D01*
G02Y877186I0J2010D01*
G01X335852D01*
G02X335851Y873166I-1J-2010D01*
G37*
G36*
G01X323253D02*
X320053D01*
G02Y877186I0J2010D01*
G01X323254D01*
G02X323253Y873166I-1J-2010D01*
G37*
G36*
G01X272859D02*
X269659D01*
G02Y877186I0J2010D01*
G01X272860D01*
G02X272859Y873166I-1J-2010D01*
G37*
G36*
G01X260261D02*
X257061D01*
G02Y877186I0J2010D01*
G01X260262D01*
G02X260261Y873166I-1J-2010D01*
G37*
G36*
G01X238213D02*
X235013D01*
G02Y877186I0J2010D01*
G01X238214D01*
G02X238213Y873166I-1J-2010D01*
G37*
G36*
G01X225615D02*
X222415D01*
G02Y877186I0J2010D01*
G01X225616D01*
G02X225615Y873166I-1J-2010D01*
G37*
G36*
G01X213017D02*
X209817D01*
G02Y877186I0J2010D01*
G01X213018D01*
G02X213017Y873166I-1J-2010D01*
G37*
G36*
G01X200418Y869666D02*
X197218D01*
G02Y873686I0J2010D01*
G01X200419D01*
G02X200418Y869666I-1J-2010D01*
G37*
G36*
G01X702400Y866790D02*
X699200D01*
G02Y870810I0J2010D01*
G01X702401D01*
G02X702400Y866790I-1J-2010D01*
G37*
G36*
G01X1198937Y865191D02*
Y865181D01*
X1195737Y865281D01*
Y865283D01*
X1195561Y865304D01*
G02X1195863Y869309I238J1996D01*
G01Y869319D01*
X1199062Y869219D01*
X1199071Y869210D01*
X1199145Y869205D01*
G02X1198937Y865191I-145J-2005D01*
G37*
G36*
G01X285500Y864190D02*
X282300D01*
G02Y868210I0J2010D01*
G01X285501D01*
G02X285500Y864190I-1J-2010D01*
G37*
G36*
G01X310955Y863666D02*
X307755D01*
G02Y867686I0J2010D01*
G01X310956D01*
G02X310955Y863666I-1J-2010D01*
G37*
G36*
G01X1350025Y828291D02*
X1346825D01*
G02Y832311I0J2010D01*
G01X1350026D01*
G02X1350025Y828291I-1J-2010D01*
G37*
G36*
G01X1337427D02*
X1334227D01*
G02Y832311I0J2010D01*
G01X1337428D01*
G02X1337427Y828291I-1J-2010D01*
G37*
G36*
G01X1324829D02*
X1321628D01*
G02X1321629Y832311I1J2010D01*
G01X1324829D01*
G02Y828291I0J-2010D01*
G37*
G36*
G01X1312231D02*
X1309030D01*
G02X1309031Y832311I1J2010D01*
G01X1312231D01*
G02Y828291I0J-2010D01*
G37*
G36*
G01X1287033D02*
X1283832D01*
G02X1283833Y832311I1J2010D01*
G01X1287033D01*
G02Y828291I0J-2010D01*
G37*
G36*
G01X1274435D02*
X1271234D01*
G02X1271235Y832311I1J2010D01*
G01X1274435D01*
G02Y828291I0J-2010D01*
G37*
G36*
G01X1261837D02*
X1258636D01*
G02X1258637Y832311I1J2010D01*
G01X1261837D01*
G02Y828291I0J-2010D01*
G37*
G36*
G01X1249239D02*
X1246038D01*
G02X1246039Y832311I1J2010D01*
G01X1249239D01*
G02Y828291I0J-2010D01*
G37*
G36*
G01X1236640D02*
X1233439D01*
G02X1233440Y832311I1J2010D01*
G01X1236640D01*
G02Y828291I0J-2010D01*
G37*
G36*
G01X1224042D02*
X1220842D01*
G02Y832311I0J2010D01*
G01X1224043D01*
G02X1224042Y828291I-1J-2010D01*
G37*
G36*
G01X1192545D02*
X1189344D01*
G02X1189345Y832311I1J2010D01*
G01X1192545D01*
G02Y828291I0J-2010D01*
G37*
G36*
G01X1179947D02*
X1176746D01*
G02X1176747Y832311I1J2010D01*
G01X1179947D01*
G02Y828291I0J-2010D01*
G37*
G36*
G01X1157899D02*
X1154698D01*
G02X1154699Y832311I1J2010D01*
G01X1157899D01*
G02Y828291I0J-2010D01*
G37*
G36*
G01X1145301D02*
X1142100D01*
G02X1142101Y832311I1J2010D01*
G01X1145301D01*
G02Y828291I0J-2010D01*
G37*
G36*
G01X1132703D02*
X1129503D01*
G02Y832311I0J2010D01*
G01X1132704D01*
G02X1132703Y828291I-1J-2010D01*
G37*
G36*
G01X1120104D02*
X1116903D01*
G02X1116904Y832311I1J2010D01*
G01X1120104D01*
G02Y828291I0J-2010D01*
G37*
G36*
G01X1107506D02*
X1104305D01*
G02X1104306Y832311I1J2010D01*
G01X1107506D01*
G02Y828291I0J-2010D01*
G37*
G36*
G01X1094907D02*
X1091706D01*
G02X1091707Y832311I1J2010D01*
G01X1094907D01*
G02Y828291I0J-2010D01*
G37*
G36*
G01X1082309D02*
X1079108D01*
G02X1079109Y832311I1J2010D01*
G01X1082309D01*
G02Y828291I0J-2010D01*
G37*
G36*
G01X1069711D02*
X1066510D01*
G02X1066511Y832311I1J2010D01*
G01X1069711D01*
G02Y828291I0J-2010D01*
G37*
G36*
G01X1057112D02*
X1053911D01*
G02X1053912Y832311I1J2010D01*
G01X1057112D01*
G02Y828291I0J-2010D01*
G37*
G36*
G01X1044514D02*
X1041313D01*
G02X1041314Y832311I1J2010D01*
G01X1044514D01*
G02Y828291I0J-2010D01*
G37*
G36*
G01X853962D02*
X850761D01*
G02X850762Y832311I1J2010D01*
G01X853962D01*
G02Y828291I0J-2010D01*
G37*
G36*
G01X841364D02*
X838163D01*
G02X838164Y832311I1J2010D01*
G01X841364D01*
G02Y828291I0J-2010D01*
G37*
G36*
G01X816167D02*
X812966D01*
G02X812967Y832311I1J2010D01*
G01X816167D01*
G02Y828291I0J-2010D01*
G37*
G36*
G01X803569D02*
X800368D01*
G02X800369Y832311I1J2010D01*
G01X803569D01*
G02Y828291I0J-2010D01*
G37*
G36*
G01X790970D02*
X787769D01*
G02X787770Y832311I1J2010D01*
G01X790970D01*
G02Y828291I0J-2010D01*
G37*
G36*
G01X778372D02*
X775171D01*
G02X775172Y832311I1J2010D01*
G01X778372D01*
G02Y828291I0J-2010D01*
G37*
G36*
G01X765774D02*
X762573D01*
G02X762574Y832311I1J2010D01*
G01X765774D01*
G02Y828291I0J-2010D01*
G37*
G36*
G01X753175D02*
X749974D01*
G02X749975Y832311I1J2010D01*
G01X753175D01*
G02Y828291I0J-2010D01*
G37*
G36*
G01X740577D02*
X737376D01*
G02X737377Y832311I1J2010D01*
G01X740577D01*
G02Y828291I0J-2010D01*
G37*
G36*
G01X727978D02*
X724777D01*
G02X724778Y832311I1J2010D01*
G01X727978D01*
G02Y828291I0J-2010D01*
G37*
G36*
G01X696482D02*
X693281D01*
G02X693282Y832311I1J2010D01*
G01X696482D01*
G02Y828291I0J-2010D01*
G37*
G36*
G01X683884D02*
X680683D01*
G02X680684Y832311I1J2010D01*
G01X683884D01*
G02Y828291I0J-2010D01*
G37*
G36*
G01X671285D02*
X668084D01*
G02X668085Y832311I1J2010D01*
G01X671285D01*
G02Y828291I0J-2010D01*
G37*
G36*
G01X658687D02*
X655486D01*
G02X655487Y832311I1J2010D01*
G01X658687D01*
G02Y828291I0J-2010D01*
G37*
G36*
G01X636640D02*
X633439D01*
G02X633440Y832311I1J2010D01*
G01X636640D01*
G02Y828291I0J-2010D01*
G37*
G36*
G01X624042D02*
X620841D01*
G02X620842Y832311I1J2010D01*
G01X624042D01*
G02Y828291I0J-2010D01*
G37*
G36*
G01X611443D02*
X608242D01*
G02X608243Y832311I1J2010D01*
G01X611443D01*
G02Y828291I0J-2010D01*
G37*
G36*
G01X598845D02*
X595644D01*
G02X595645Y832311I1J2010D01*
G01X598845D01*
G02Y828291I0J-2010D01*
G37*
G36*
G01X586246D02*
X583045D01*
G02X583046Y832311I1J2010D01*
G01X586246D01*
G02Y828291I0J-2010D01*
G37*
G36*
G01X573648D02*
X570447D01*
G02X570448Y832311I1J2010D01*
G01X573648D01*
G02Y828291I0J-2010D01*
G37*
G36*
G01X561050D02*
X557849D01*
G02X557850Y832311I1J2010D01*
G01X561050D01*
G02Y828291I0J-2010D01*
G37*
G36*
G01X548451D02*
X545250D01*
G02X545251Y832311I1J2010D01*
G01X548451D01*
G02Y828291I0J-2010D01*
G37*
G36*
G01X427191D02*
X423990D01*
G02X423991Y832311I1J2010D01*
G01X427191D01*
G02Y828291I0J-2010D01*
G37*
G36*
G01X414593D02*
X411392D01*
G02X411393Y832311I1J2010D01*
G01X414593D01*
G02Y828291I0J-2010D01*
G37*
G36*
G01X401994D02*
X398794D01*
G02Y832311I0J2010D01*
G01X401995D01*
G02X401994Y828291I-1J-2010D01*
G37*
G36*
G01X389396D02*
X386195D01*
G02X386196Y832311I1J2010D01*
G01X389396D01*
G02Y828291I0J-2010D01*
G37*
G36*
G01X367348D02*
X364147D01*
G02X364148Y832311I1J2010D01*
G01X367348D01*
G02Y828291I0J-2010D01*
G37*
G36*
G01X354750D02*
X351549D01*
G02X351550Y832311I1J2010D01*
G01X354750D01*
G02Y828291I0J-2010D01*
G37*
G36*
G01X342151D02*
X338950D01*
G02X338951Y832311I1J2010D01*
G01X342151D01*
G02Y828291I0J-2010D01*
G37*
G36*
G01X329553D02*
X326352D01*
G02X326353Y832311I1J2010D01*
G01X329553D01*
G02Y828291I0J-2010D01*
G37*
G36*
G01X316954D02*
X313753D01*
G02X313754Y832311I1J2010D01*
G01X316954D01*
G02Y828291I0J-2010D01*
G37*
G36*
G01X279159D02*
X275958D01*
G02X275959Y832311I1J2010D01*
G01X279159D01*
G02Y828291I0J-2010D01*
G37*
G36*
G01X266561D02*
X263360D01*
G02X263361Y832311I1J2010D01*
G01X266561D01*
G02Y828291I0J-2010D01*
G37*
G36*
G01X253962D02*
X250761D01*
G02X250762Y832311I1J2010D01*
G01X253962D01*
G02Y828291I0J-2010D01*
G37*
G36*
G01X231915D02*
X228714D01*
G02X228715Y832311I1J2010D01*
G01X231915D01*
G02Y828291I0J-2010D01*
G37*
G36*
G01X219317D02*
X216117D01*
G02Y832311I0J2010D01*
G01X219318D01*
G02X219317Y828291I-1J-2010D01*
G37*
G36*
G01X206718D02*
X203517D01*
G02X203518Y832311I1J2010D01*
G01X206718D01*
G02Y828291I0J-2010D01*
G37*
G36*
G01X194120D02*
X190919D01*
G02X190920Y832311I1J2010D01*
G01X194120D01*
G02Y828291I0J-2010D01*
G37*
G36*
G01X200620Y819691D02*
X197419D01*
G02X197420Y823711I1J2010D01*
G01X200620D01*
G02Y819691I0J-2010D01*
G37*
G36*
G01X370875Y720990D02*
X367675D01*
G02Y725010I0J2010D01*
G01X370876D01*
G02X370875Y720990I-1J-2010D01*
G37*
G36*
G01X1225348Y135950D02*
X1222148D01*
G02Y139970I0J2010D01*
G01X1225349D01*
G02X1225348Y135950I-1J-2010D01*
G37*
G36*
G01X1190835Y135889D02*
X1187635D01*
G02Y139909I0J2010D01*
G01X1190836D01*
G02X1190835Y135889I-1J-2010D01*
G37*
G36*
G01X1242900Y135841D02*
X1239700D01*
G02Y139861I0J2010D01*
G01X1242901D01*
G02X1242900Y135841I-1J-2010D01*
G37*
G36*
G01X718790Y114150D02*
Y117350D01*
G02X722810I2010J0D01*
G01Y114149D01*
G02X718790Y114150I-2010J1D01*
G37*
G36*
G01X568342Y92882D02*
X568235Y93048D01*
X568234Y93047D01*
X565281Y98559D01*
X565284Y98561D01*
X565213Y98720D01*
G02X569627Y100887I2245J1005D01*
G01X569721Y100710D01*
X569729Y100715D01*
X572588Y95380D01*
X572583Y95375D01*
X572642Y95249D01*
G02X568342Y92882I-2231J-1036D01*
G37*
G36*
G01X1170704D02*
X1170597Y93048D01*
X1170596Y93047D01*
X1167643Y98559D01*
X1167646Y98561D01*
X1167575Y98720D01*
G02X1171989Y100887I2245J1005D01*
G01X1172083Y100710D01*
X1172091Y100715D01*
X1174950Y95380D01*
X1174945Y95375D01*
X1175004Y95249D01*
G02X1170704Y92882I-2231J-1036D01*
G37*
G36*
G01X1222870D02*
X1222763Y93048D01*
X1222762Y93047D01*
X1219809Y98558D01*
X1219814Y98563D01*
X1219755Y98689D01*
G02X1224155Y100887I2231J1036D01*
G01X1224249Y100710D01*
X1224257Y100715D01*
X1227116Y95379D01*
X1227113Y95377D01*
X1227184Y95218D01*
G02X1222870Y92882I-2246J-1004D01*
G37*
G36*
G01X1188421D02*
X1188314Y93048D01*
X1188313Y93047D01*
X1185360Y98558D01*
X1185365Y98563D01*
X1185306Y98689D01*
G02X1189706Y100887I2231J1036D01*
G01X1189800Y100710D01*
X1189808Y100715D01*
X1192667Y95379D01*
X1192664Y95377D01*
X1192735Y95218D01*
G02X1188421Y92882I-2246J-1004D01*
G37*
G36*
G01X672673D02*
X672566Y93048D01*
X672565Y93047D01*
X669612Y98558D01*
X669617Y98563D01*
X669558Y98689D01*
G02X673958Y100887I2231J1036D01*
G01X674052Y100710D01*
X674060Y100715D01*
X676919Y95379D01*
X676916Y95377D01*
X676987Y95218D01*
G02X672673Y92882I-2246J-1004D01*
G37*
G36*
G01X663815D02*
X663708Y93048D01*
X663707Y93047D01*
X660754Y98558D01*
X660759Y98563D01*
X660700Y98689D01*
G02X665100Y100887I2231J1036D01*
G01X665194Y100710D01*
X665202Y100715D01*
X668061Y95379D01*
X668058Y95377D01*
X668129Y95218D01*
G02X663815Y92882I-2246J-1004D01*
G37*
G36*
G01X629366D02*
X629259Y93048D01*
X629258Y93047D01*
X626305Y98558D01*
X626310Y98563D01*
X626251Y98689D01*
G02X630651Y100887I2231J1036D01*
G01X630745Y100710D01*
X630753Y100715D01*
X633612Y95379D01*
X633609Y95377D01*
X633680Y95218D01*
G02X629366Y92882I-2246J-1004D01*
G37*
G36*
G01X620508D02*
X620401Y93048D01*
X620400Y93047D01*
X617447Y98558D01*
X617452Y98563D01*
X617393Y98689D01*
G02X621793Y100887I2231J1036D01*
G01X621887Y100710D01*
X621895Y100715D01*
X624754Y95379D01*
X624751Y95377D01*
X624822Y95218D01*
G02X620508Y92882I-2246J-1004D01*
G37*
G36*
G01X586059D02*
X585952Y93048D01*
X585951Y93047D01*
X582998Y98558D01*
X583003Y98563D01*
X582944Y98689D01*
G02X587344Y100887I2231J1036D01*
G01X587438Y100710D01*
X587446Y100715D01*
X590305Y95379D01*
X590302Y95377D01*
X590373Y95218D01*
G02X586059Y92882I-2246J-1004D01*
G37*
G36*
G01X542752D02*
X542645Y93048D01*
X542644Y93047D01*
X539691Y98558D01*
X539696Y98563D01*
X539637Y98689D01*
G02X544037Y100887I2231J1036D01*
G01X544131Y100710D01*
X544139Y100715D01*
X546998Y95379D01*
X546995Y95377D01*
X547066Y95218D01*
G02X542752Y92882I-2246J-1004D01*
G37*
G36*
G01X533793Y93052D02*
X530857Y98534D01*
X530856Y98535D01*
G02X535179Y100886I2154J1190D01*
G01X538131Y95374D01*
G02X533793Y93052I-2169J-1161D01*
G37*
G36*
G01X525035Y92882D02*
X524928Y93048D01*
X524927Y93047D01*
X521974Y98558D01*
X521979Y98563D01*
X521920Y98689D01*
G02X526320Y100887I2231J1036D01*
G01X526414Y100710D01*
X526422Y100715D01*
X529281Y95379D01*
X529278Y95377D01*
X529349Y95218D01*
G02X525035Y92882I-2246J-1004D01*
G37*
G36*
G01X1257218Y93052D02*
X1254266Y98564D01*
G02X1256412Y102185I2169J1161D01*
G02X1258604Y100886I23J-2460D01*
G01X1261540Y95404D01*
X1261541Y95403D01*
G02X1257218Y93052I-2154J-1190D01*
G37*
G36*
G01X1213911D02*
X1210959Y98564D01*
G02X1215297Y100886I2169J1161D01*
G01X1218233Y95404D01*
X1218234Y95403D01*
G02X1213911Y93052I-2154J-1190D01*
G37*
G36*
G01X654856D02*
X651904Y98564D01*
G02X656242Y100886I2169J1161D01*
G01X659178Y95404D01*
X659179Y95403D01*
G02X654856Y93052I-2154J-1190D01*
G37*
G36*
G01X611549D02*
X608597Y98564D01*
G02X612935Y100886I2169J1161D01*
G01X615871Y95404D01*
X615872Y95403D01*
G02X611549Y93052I-2154J-1190D01*
G37*
G36*
G01X718790Y93150D02*
Y96351D01*
G02X722810Y96350I2010J-1D01*
G01Y93150D01*
G02X718790I-2010J0D01*
G37*
G36*
G01X672673Y77921D02*
X672566Y78087D01*
X672565Y78086D01*
X669612Y83598D01*
X669615Y83600D01*
X669544Y83759D01*
G02X673958Y85926I2245J1005D01*
G01X674052Y85749D01*
X674060Y85754D01*
X676919Y80419D01*
X676914Y80414D01*
X676973Y80288D01*
G02X672673Y77921I-2231J-1036D01*
G37*
G36*
G01X663815D02*
X663708Y78087D01*
X663707Y78086D01*
X660754Y83598D01*
X660757Y83600D01*
X660686Y83759D01*
G02X665100Y85926I2245J1005D01*
G01X665194Y85749D01*
X665202Y85754D01*
X668061Y80419D01*
X668056Y80414D01*
X668115Y80288D01*
G02X663815Y77921I-2231J-1036D01*
G37*
G36*
G01X586059D02*
X585952Y78087D01*
X585951Y78086D01*
X582998Y83598D01*
X583001Y83600D01*
X582930Y83759D01*
G02X587344Y85926I2245J1005D01*
G01X587438Y85749D01*
X587446Y85754D01*
X590305Y80419D01*
X590300Y80414D01*
X590359Y80288D01*
G02X586059Y77921I-2231J-1036D01*
G37*
G36*
G01X1188421D02*
X1188314Y78087D01*
X1188313Y78086D01*
X1185360Y83598D01*
X1185363Y83600D01*
X1185292Y83759D01*
G02X1189706Y85926I2245J1005D01*
G01X1189800Y85749D01*
X1189808Y85754D01*
X1192667Y80419D01*
X1192662Y80414D01*
X1192721Y80288D01*
G02X1188421Y77921I-2231J-1036D01*
G37*
G36*
G01X1145114D02*
X1145007Y78087D01*
X1145006Y78086D01*
X1142053Y83597D01*
X1142058Y83602D01*
X1141999Y83728D01*
G02X1146399Y85926I2231J1036D01*
G01X1146493Y85749D01*
X1146501Y85754D01*
X1149360Y80418D01*
X1149357Y80416D01*
X1149428Y80257D01*
G02X1145114Y77921I-2246J-1004D01*
G37*
G36*
G01X533793Y78091D02*
X530857Y83573D01*
X530856Y83574D01*
G02X535179Y85925I2154J1190D01*
G01X538131Y80413D01*
G02X533793Y78091I-2169J-1161D01*
G37*
G36*
G01X1179462D02*
X1176510Y83603D01*
G02X1180848Y85925I2169J1161D01*
G01X1183784Y80443D01*
X1183785Y80442D01*
G02X1179462Y78091I-2154J-1190D01*
G37*
G36*
G01X1101339Y70669D02*
X1101290Y73869D01*
G02X1105310Y73931I2010J31D01*
G01X1105359Y70732D01*
G02X1101339Y70669I-2010J-32D01*
G37*
G36*
G01X1170704Y48000D02*
X1170597Y48166D01*
X1170596Y48165D01*
X1167643Y53676D01*
X1167648Y53681D01*
X1167589Y53807D01*
G02X1171989Y56005I2231J1036D01*
G01X1172083Y55828D01*
X1172091Y55833D01*
X1174950Y50497D01*
X1174947Y50495D01*
X1175018Y50336D01*
G02X1170704Y48000I-2246J-1004D01*
G37*
G36*
G01X568342D02*
X568235Y48166D01*
X568234Y48165D01*
X565281Y53676D01*
X565286Y53681D01*
X565227Y53807D01*
G02X569627Y56005I2231J1036D01*
G01X569721Y55828D01*
X569729Y55833D01*
X572588Y50497D01*
X572585Y50495D01*
X572656Y50336D01*
G02X568342Y48000I-2246J-1004D01*
G37*
G36*
G01X1292817Y139490D02*
X1296018D01*
G02X1296017Y135466I-1J-2012D01*
G01X1292817D01*
G02Y139490I0J2012D01*
G37*
G36*
G01X1283343Y143592D02*
X1286544D01*
G02X1286543Y139570I-1J-2011D01*
G01X1283343D01*
G02Y143592I0J2011D01*
G37*
G36*
G01X1261944Y143758D02*
X1258743D01*
G02X1258744Y147782I1J2012D01*
G01X1261944D01*
G02Y143758I0J-2012D01*
G37*
G36*
G01X1277265Y135662D02*
X1274064D01*
G02X1274065Y139684I1J2011D01*
G01X1277265D01*
G02Y135662I0J-2011D01*
G37*
G36*
G01X1266177Y92880D02*
X1266070Y93046D01*
X1266068Y93045D01*
X1263114Y98558D01*
X1263119Y98563D01*
X1263060Y98690D01*
G02X1267463Y100888I2233J1035D01*
G01X1267557Y100712D01*
X1267565Y100716D01*
X1270425Y95378D01*
X1270422Y95377D01*
X1270493Y95218D01*
G02X1266177Y92880I-2248J-1004D01*
G37*
G36*
G01Y77919D02*
X1266070Y78085D01*
X1266068Y78084D01*
X1263114Y83599D01*
X1263117Y83600D01*
X1263046Y83759D01*
G02X1267463Y85927I2247J1006D01*
G01X1267557Y85751D01*
X1267565Y85755D01*
X1270425Y80419D01*
X1270420Y80414D01*
X1270479Y80287D01*
G02X1266177Y77919I-2234J-1034D01*
G37*
G36*
G01X1275035D02*
X1274928Y78085D01*
X1274926Y78084D01*
X1271972Y83599D01*
X1271975Y83600D01*
X1271904Y83759D01*
G02X1276321Y85927I2247J1006D01*
G01X1276415Y85751D01*
X1276423Y85755D01*
X1279283Y80419D01*
X1279278Y80414D01*
X1279337Y80287D01*
G02X1275035Y77919I-2234J-1034D01*
G37*
G36*
G01Y92880D02*
X1274928Y93046D01*
X1274926Y93045D01*
X1271972Y98558D01*
X1271977Y98563D01*
X1271918Y98690D01*
G02X1276321Y100888I2233J1035D01*
G01X1276415Y100712D01*
X1276423Y100716D01*
X1279283Y95378D01*
X1279280Y95377D01*
X1279351Y95218D01*
G02X1275035Y92880I-2248J-1004D01*
G37*
G36*
G01X1258605Y56005D02*
X1261557Y50493D01*
G02X1257217Y48169I-2170J-1162D01*
G01X1254281Y53651D01*
X1254280Y53652D01*
G02X1258605Y56005I2155J1191D01*
G37*
G36*
G01X1275035Y47998D02*
X1274928Y48164D01*
X1274926Y48163D01*
X1271972Y53676D01*
X1271977Y53681D01*
X1271918Y53808D01*
G02X1276321Y56006I2233J1035D01*
G01X1276415Y55830D01*
X1276423Y55834D01*
X1279283Y50496D01*
X1279280Y50495D01*
X1279351Y50336D01*
G02X1275035Y47998I-2248J-1004D01*
G37*
G36*
G01X1266177D02*
X1266070Y48164D01*
X1266068Y48163D01*
X1263114Y53676D01*
X1263119Y53681D01*
X1263060Y53808D01*
G02X1267463Y56006I2233J1035D01*
G01X1267557Y55830D01*
X1267565Y55834D01*
X1270425Y50496D01*
X1270422Y50495D01*
X1270493Y50336D01*
G02X1266177Y47998I-2248J-1004D01*
G37*
G36*
G01X1275030Y62966D02*
X1274929Y63124D01*
X1274926Y63123D01*
X1271972Y68636D01*
X1271977Y68641D01*
X1271918Y68768D01*
G02X1276320Y70967I2233J1035D01*
G01X1276414Y70791D01*
X1276423Y70796D01*
X1279283Y65458D01*
X1279280Y65457D01*
X1279354Y65290D01*
G02X1275030Y62966I-2250J-999D01*
G37*
G36*
G01X1266172D02*
X1266071Y63124D01*
X1266068Y63123D01*
X1263114Y68636D01*
X1263119Y68641D01*
X1263060Y68768D01*
G02X1267462Y70967I2233J1035D01*
G01X1267556Y70791D01*
X1267565Y70796D01*
X1270425Y65458D01*
X1270422Y65457D01*
X1270496Y65290D01*
G02X1266172Y62966I-2250J-999D01*
G37*
G36*
G01X1234209Y140452D02*
X1231008D01*
G02X1231009Y144474I1J2011D01*
G01X1234209D01*
G02Y140452I0J-2011D01*
G37*
G36*
G01X1222870Y77919D02*
X1222763Y78085D01*
X1222761Y78084D01*
X1219807Y83599D01*
X1219810Y83600D01*
X1219739Y83759D01*
G02X1224156Y85927I2247J1006D01*
G01X1224250Y85751D01*
X1224258Y85755D01*
X1227118Y80419D01*
X1227113Y80414D01*
X1227172Y80287D01*
G02X1222870Y77919I-2234J-1034D01*
G37*
G36*
G01X1231728Y92880D02*
X1231621Y93046D01*
X1231619Y93045D01*
X1228665Y98558D01*
X1228670Y98563D01*
X1228611Y98690D01*
G02X1233014Y100888I2233J1035D01*
G01X1233108Y100712D01*
X1233116Y100716D01*
X1235976Y95378D01*
X1235973Y95377D01*
X1236044Y95218D01*
G02X1231728Y92880I-2248J-1004D01*
G37*
G36*
G01Y77919D02*
X1231621Y78085D01*
X1231619Y78084D01*
X1228665Y83599D01*
X1228668Y83600D01*
X1228597Y83759D01*
G02X1233014Y85927I2247J1006D01*
G01X1233108Y85751D01*
X1233116Y85755D01*
X1235976Y80419D01*
X1235971Y80414D01*
X1236030Y80287D01*
G02X1231728Y77919I-2234J-1034D01*
G37*
G36*
G01Y47998D02*
X1231621Y48164D01*
X1231619Y48163D01*
X1228665Y53676D01*
X1228670Y53681D01*
X1228611Y53808D01*
G02X1233014Y56006I2233J1035D01*
G01X1233108Y55830D01*
X1233116Y55834D01*
X1235976Y50496D01*
X1235973Y50495D01*
X1236044Y50336D01*
G02X1231728Y47998I-2248J-1004D01*
G37*
G36*
G01X1222870D02*
X1222763Y48164D01*
X1222761Y48163D01*
X1219807Y53676D01*
X1219812Y53681D01*
X1219753Y53808D01*
G02X1224156Y56006I2233J1035D01*
G01X1224250Y55830D01*
X1224258Y55834D01*
X1227118Y50496D01*
X1227115Y50495D01*
X1227186Y50336D01*
G02X1222870Y47998I-2248J-1004D01*
G37*
G36*
G01X1231723Y62966D02*
X1231622Y63124D01*
X1231619Y63123D01*
X1228665Y68636D01*
X1228670Y68641D01*
X1228611Y68768D01*
G02X1233013Y70967I2233J1035D01*
G01X1233107Y70791D01*
X1233116Y70796D01*
X1235976Y65458D01*
X1235973Y65457D01*
X1236047Y65290D01*
G02X1231723Y62966I-2250J-999D01*
G37*
G36*
G01X1222865D02*
X1222764Y63124D01*
X1222761Y63123D01*
X1219807Y68636D01*
X1219812Y68641D01*
X1219753Y68768D01*
G02X1224155Y70967I2233J1035D01*
G01X1224249Y70791D01*
X1224258Y70796D01*
X1227118Y65458D01*
X1227115Y65457D01*
X1227189Y65290D01*
G02X1222865Y62966I-2250J-999D01*
G37*
G36*
G01X1203791Y158742D02*
X1206992D01*
G02X1206991Y154718I-1J-2012D01*
G01X1203791D01*
G02Y158742I0J2012D01*
G37*
G36*
G01X1196200Y144862D02*
X1199401D01*
G02X1199400Y140840I-1J-2011D01*
G01X1196200D01*
G02Y144862I0J2011D01*
G37*
G36*
G01X1215298Y56005D02*
X1218250Y50493D01*
G02X1213910Y48169I-2170J-1162D01*
G01X1210974Y53651D01*
X1210973Y53652D01*
G02X1215298Y56005I2155J1191D01*
G37*
G36*
G01X1188421Y47998D02*
X1188314Y48164D01*
X1188312Y48163D01*
X1185358Y53676D01*
X1185363Y53681D01*
X1185304Y53808D01*
G02X1189707Y56006I2233J1035D01*
G01X1189801Y55830D01*
X1189809Y55834D01*
X1192669Y50496D01*
X1192666Y50495D01*
X1192737Y50336D01*
G02X1188421Y47998I-2248J-1004D01*
G37*
G36*
G01X1188416Y62966D02*
X1188315Y63124D01*
X1188312Y63123D01*
X1185358Y68636D01*
X1185363Y68641D01*
X1185304Y68768D01*
G02X1189706Y70967I2233J1035D01*
G01X1189800Y70791D01*
X1189809Y70796D01*
X1192669Y65458D01*
X1192666Y65457D01*
X1192740Y65290D01*
G02X1188416Y62966I-2250J-999D01*
G37*
G36*
G01X1182061Y140466D02*
X1178860D01*
G02X1178861Y144490I1J2012D01*
G01X1182061D01*
G02Y140466I0J-2012D01*
G37*
G36*
G01X1180849Y100887D02*
X1183801Y95375D01*
G02X1179461Y93051I-2170J-1162D01*
G01X1176525Y98533D01*
X1176524Y98534D01*
G02X1180849Y100887I2155J1191D01*
G37*
G36*
G01Y56005D02*
X1183801Y50493D01*
G02X1179461Y48169I-2170J-1162D01*
G01X1176525Y53651D01*
X1176524Y53652D01*
G02X1180849Y56005I2155J1191D01*
G37*
G36*
G01X1179562Y62959D02*
X1179455Y63125D01*
X1179453Y63124D01*
X1176500Y68636D01*
X1176505Y68641D01*
X1176446Y68768D01*
G02X1180849Y70966I2233J1035D01*
G01X1180943Y70790D01*
X1180951Y70794D01*
X1183810Y65457D01*
X1183807Y65456D01*
X1183878Y65297D01*
G02X1179562Y62959I-2248J-1004D01*
G37*
G36*
G01X1127397Y92880D02*
X1127290Y93046D01*
X1127288Y93045D01*
X1124334Y98558D01*
X1124339Y98563D01*
X1124280Y98690D01*
G02X1128683Y100888I2233J1035D01*
G01X1128777Y100712D01*
X1128785Y100716D01*
X1131645Y95378D01*
X1131642Y95377D01*
X1131713Y95218D01*
G02X1127397Y92880I-2248J-1004D01*
G37*
G36*
G01X1137542Y100887D02*
X1140494Y95375D01*
G02X1136154Y93051I-2170J-1162D01*
G01X1133218Y98533D01*
X1133217Y98534D01*
G02X1137542Y100887I2155J1191D01*
G37*
G36*
G01X1111088Y81902D02*
X1111198Y82050D01*
X1111197Y82052D01*
X1113341Y84432D01*
X1113343Y84430D01*
X1113475Y84553D01*
G02X1116337Y81733I1367J-1475D01*
G01X1116203Y81585D01*
X1116211Y81578D01*
X1114203Y79348D01*
X1114192D01*
X1114133Y79288D01*
G02X1111088Y81902I-1432J1412D01*
G37*
G36*
G01X1145114Y92880D02*
X1145007Y93046D01*
X1145005Y93045D01*
X1142051Y98558D01*
X1142056Y98563D01*
X1141997Y98690D01*
G02X1146400Y100888I2233J1035D01*
G01X1146494Y100712D01*
X1146502Y100716D01*
X1149362Y95378D01*
X1149359Y95377D01*
X1149430Y95218D01*
G02X1145114Y92880I-2248J-1004D01*
G37*
G36*
G01X1137542Y85926D02*
X1140494Y80414D01*
G02X1136154Y78090I-2170J-1162D01*
G01X1133218Y83572D01*
X1133217Y83573D01*
G02X1137542Y85926I2155J1191D01*
G37*
G36*
G01X1127397Y47998D02*
X1127290Y48164D01*
X1127288Y48163D01*
X1124334Y53678D01*
X1124337Y53679D01*
X1124266Y53838D01*
G02X1128683Y56006I2247J1006D01*
G01X1128777Y55830D01*
X1128785Y55834D01*
X1131645Y50498D01*
X1131640Y50493D01*
X1131699Y50366D01*
G02X1127397Y47998I-2234J-1034D01*
G37*
G36*
G01X1145114D02*
X1145007Y48164D01*
X1145005Y48163D01*
X1142051Y53678D01*
X1142054Y53679D01*
X1141983Y53838D01*
G02X1146400Y56006I2247J1006D01*
G01X1146494Y55830D01*
X1146502Y55834D01*
X1149362Y50498D01*
X1149357Y50493D01*
X1149416Y50366D01*
G02X1145114Y47998I-2234J-1034D01*
G37*
G36*
G01X1137542Y56005D02*
X1140478Y50523D01*
X1140479Y50522D01*
G02X1136154Y48169I-2155J-1191D01*
G01X1133202Y53681D01*
G02X1137542Y56005I2170J1162D01*
G37*
G36*
G01X1145109Y62966D02*
X1145008Y63124D01*
X1145005Y63123D01*
X1142051Y68636D01*
X1142056Y68641D01*
X1141997Y68768D01*
G02X1146399Y70967I2233J1035D01*
G01X1146493Y70791D01*
X1146502Y70796D01*
X1149362Y65458D01*
X1149359Y65457D01*
X1149433Y65290D01*
G02X1145109Y62966I-2250J-999D01*
G37*
G36*
G01X1136255Y62959D02*
X1136148Y63125D01*
X1136146Y63124D01*
X1133193Y68636D01*
X1133198Y68641D01*
X1133139Y68768D01*
G02X1137542Y70966I2233J1035D01*
G01X1137636Y70790D01*
X1137644Y70794D01*
X1140503Y65457D01*
X1140500Y65456D01*
X1140571Y65297D01*
G02X1136255Y62959I-2248J-1004D01*
G37*
G36*
G01X722812Y81350D02*
Y78149D01*
G02X718788Y78150I-2012J1D01*
G01Y81350D01*
G02X722812I2012J0D01*
G37*
G36*
G01X734512Y101621D02*
Y98420D01*
G02X730488Y98421I-2012J1D01*
G01Y101621D01*
G02X734512I2012J0D01*
G37*
G36*
G01X722812Y105350D02*
Y102149D01*
G02X718788Y102150I-2012J1D01*
G01Y105350D01*
G02X722812I2012J0D01*
G37*
G36*
G01X683600Y376706D02*
X680099D01*
G02X680100Y380730I1J2012D01*
G01X683600D01*
G02Y376706I0J-2012D01*
G37*
G36*
G01X662256Y352200D02*
Y348999D01*
G02X658232Y349000I-2012J1D01*
G01Y352200D01*
G02X662256I2012J0D01*
G37*
G36*
G01X640550Y323512D02*
X643751D01*
G02X643750Y319488I-1J-2012D01*
G01X640550D01*
G02Y323512I0J2012D01*
G37*
G36*
G01X656243Y56005D02*
X659195Y50493D01*
G02X654855Y48169I-2170J-1162D01*
G01X651919Y53651D01*
X651918Y53652D01*
G02X656243Y56005I2155J1191D01*
G37*
G36*
G01X663815Y47998D02*
X663708Y48164D01*
X663706Y48163D01*
X660752Y53676D01*
X660757Y53681D01*
X660698Y53808D01*
G02X665101Y56006I2233J1035D01*
G01X665195Y55830D01*
X665203Y55834D01*
X668063Y50496D01*
X668060Y50495D01*
X668131Y50336D01*
G02X663815Y47998I-2248J-1004D01*
G37*
G36*
G01X663810Y62966D02*
X663709Y63124D01*
X663706Y63123D01*
X660752Y68636D01*
X660757Y68641D01*
X660698Y68768D01*
G02X665100Y70967I2233J1035D01*
G01X665194Y70791D01*
X665203Y70796D01*
X668063Y65458D01*
X668060Y65457D01*
X668134Y65290D01*
G02X663810Y62966I-2250J-999D01*
G37*
G36*
G01X672668D02*
X672567Y63124D01*
X672564Y63123D01*
X669610Y68636D01*
X669615Y68641D01*
X669556Y68768D01*
G02X673958Y70967I2233J1035D01*
G01X674052Y70791D01*
X674061Y70796D01*
X676921Y65458D01*
X676918Y65457D01*
X676992Y65290D01*
G02X672668Y62966I-2250J-999D01*
G37*
G36*
G01X672673Y47998D02*
X672566Y48164D01*
X672564Y48163D01*
X669610Y53676D01*
X669615Y53681D01*
X669556Y53808D01*
G02X673959Y56006I2233J1035D01*
G01X674053Y55830D01*
X674061Y55834D01*
X676921Y50496D01*
X676918Y50495D01*
X676989Y50336D01*
G02X672673Y47998I-2248J-1004D01*
G37*
G36*
G01X636950Y151662D02*
X640151D01*
G02X640150Y147638I-1J-2012D01*
G01X636950D01*
G02Y151662I0J2012D01*
G37*
G36*
G01X638150Y135868D02*
X634949D01*
G02X634950Y139892I1J2012D01*
G01X638150D01*
G02Y135868I0J-2012D01*
G37*
G36*
G01X627826D02*
X624625D01*
G02X624626Y139892I1J2012D01*
G01X627826D01*
G02Y135868I0J-2012D01*
G37*
G36*
G01X629366Y77919D02*
X629259Y78085D01*
X629257Y78084D01*
X626303Y83599D01*
X626306Y83600D01*
X626235Y83759D01*
G02X630652Y85927I2247J1006D01*
G01X630746Y85751D01*
X630754Y85755D01*
X633614Y80419D01*
X633609Y80414D01*
X633668Y80287D01*
G02X629366Y77919I-2234J-1034D01*
G37*
G36*
G01X612936Y56005D02*
X615888Y50493D01*
G02X611548Y48169I-2170J-1162D01*
G01X608612Y53651D01*
X608611Y53652D01*
G02X612936Y56005I2155J1191D01*
G37*
G36*
G01X629366Y47998D02*
X629259Y48164D01*
X629257Y48163D01*
X626303Y53676D01*
X626308Y53681D01*
X626249Y53808D01*
G02X630652Y56006I2233J1035D01*
G01X630746Y55830D01*
X630754Y55834D01*
X633614Y50496D01*
X633611Y50495D01*
X633682Y50336D01*
G02X629366Y47998I-2248J-1004D01*
G37*
G36*
G01X629361Y62966D02*
X629260Y63124D01*
X629257Y63123D01*
X626303Y68636D01*
X626308Y68641D01*
X626249Y68768D01*
G02X630651Y70967I2233J1035D01*
G01X630745Y70791D01*
X630754Y70796D01*
X633614Y65458D01*
X633611Y65457D01*
X633685Y65290D01*
G02X629361Y62966I-2250J-999D01*
G37*
G36*
G01X620503D02*
X620402Y63124D01*
X620399Y63123D01*
X617445Y68636D01*
X617450Y68641D01*
X617391Y68768D01*
G02X621793Y70967I2233J1035D01*
G01X621887Y70791D01*
X621896Y70796D01*
X624756Y65458D01*
X624753Y65457D01*
X624827Y65290D01*
G02X620503Y62966I-2250J-999D01*
G37*
G36*
G01X620508Y47998D02*
X620401Y48164D01*
X620399Y48163D01*
X617445Y53676D01*
X617450Y53681D01*
X617391Y53808D01*
G02X621794Y56006I2233J1035D01*
G01X621888Y55830D01*
X621896Y55834D01*
X624756Y50496D01*
X624753Y50495D01*
X624824Y50336D01*
G02X620508Y47998I-2248J-1004D01*
G37*
G36*
G01X594150Y151962D02*
X597351D01*
G02X597350Y147938I-1J-2012D01*
G01X594150D01*
G02Y151962I0J2012D01*
G37*
G36*
G01X601250Y139792D02*
X604451D01*
G02X604450Y135768I-1J-2012D01*
G01X601250D01*
G02Y139792I0J2012D01*
G37*
G36*
G01X584650Y139812D02*
X587851D01*
G02X587850Y135788I-1J-2012D01*
G01X584650D01*
G02Y139812I0J2012D01*
G37*
G36*
G01X577650Y135768D02*
X574449D01*
G02X574450Y139792I1J2012D01*
G01X577650D01*
G02Y135768I0J-2012D01*
G37*
G36*
G01X578487Y85926D02*
X581423Y80444D01*
X581424Y80443D01*
G02X577099Y78090I-2155J-1191D01*
G01X574147Y83602D01*
G02X578487Y85926I2170J1162D01*
G37*
G36*
G01X577099Y93051D02*
X574163Y98533D01*
X574162Y98534D01*
G02X578487Y100887I2155J1191D01*
G01X581439Y95375D01*
G02X577099Y93051I-2170J-1162D01*
G37*
G36*
G01X586054Y62966D02*
X585953Y63124D01*
X585950Y63123D01*
X582996Y68636D01*
X583001Y68641D01*
X582942Y68768D01*
G02X587344Y70967I2233J1035D01*
G01X587438Y70791D01*
X587447Y70796D01*
X590307Y65458D01*
X590304Y65457D01*
X590378Y65290D01*
G02X586054Y62966I-2250J-999D01*
G37*
G36*
G01X577200Y62959D02*
X577093Y63125D01*
X577091Y63124D01*
X574138Y68636D01*
X574143Y68641D01*
X574084Y68768D01*
G02X578487Y70966I2233J1035D01*
G01X578581Y70790D01*
X578589Y70794D01*
X581448Y65457D01*
X581445Y65456D01*
X581516Y65297D01*
G02X577200Y62959I-2248J-1004D01*
G37*
G36*
G01X586059Y47998D02*
X585952Y48164D01*
X585950Y48163D01*
X582996Y53676D01*
X583001Y53681D01*
X582942Y53808D01*
G02X587345Y56006I2233J1035D01*
G01X587439Y55830D01*
X587447Y55834D01*
X590307Y50496D01*
X590304Y50495D01*
X590375Y50336D01*
G02X586059Y47998I-2248J-1004D01*
G37*
G36*
G01X578487Y56005D02*
X581439Y50493D01*
G02X577099Y48169I-2170J-1162D01*
G01X574163Y53651D01*
X574162Y53652D01*
G02X578487Y56005I2155J1191D01*
G37*
G36*
G01X548700Y150188D02*
X545499D01*
G02X545500Y154212I1J2012D01*
G01X548700D01*
G02Y150188I0J-2012D01*
G37*
G36*
G01X541600Y139780D02*
X544801D01*
G02X544800Y135758I-1J-2011D01*
G01X541600D01*
G02Y139780I0J2011D01*
G37*
G36*
G01X542752Y47998D02*
X542645Y48164D01*
X542643Y48163D01*
X539689Y53678D01*
X539692Y53679D01*
X539621Y53838D01*
G02X544038Y56006I2247J1006D01*
G01X544132Y55830D01*
X544140Y55834D01*
X547000Y50498D01*
X546995Y50493D01*
X547054Y50366D01*
G02X542752Y47998I-2234J-1034D01*
G37*
G36*
G01X542747Y62966D02*
X542646Y63124D01*
X542643Y63123D01*
X539689Y68636D01*
X539694Y68641D01*
X539635Y68768D01*
G02X544037Y70967I2233J1035D01*
G01X544131Y70791D01*
X544140Y70796D01*
X547000Y65458D01*
X546997Y65457D01*
X547071Y65290D01*
G02X542747Y62966I-2250J-999D01*
G37*
G36*
G01X521098Y168200D02*
Y163799D01*
G02X516274Y163800I-2412J1D01*
G01Y168200D01*
G02X521098I2412J0D01*
G37*
G36*
G01X526977Y142720D02*
X530178D01*
G02X530177Y138696I-1J-2012D01*
G01X526977D01*
G02Y142720I0J2012D01*
G37*
G36*
G01X519300Y136860D02*
X516099D01*
G02X516100Y140882I1J2011D01*
G01X519300D01*
G02Y136860I0J-2011D01*
G37*
G36*
G01X525035Y47998D02*
X524928Y48164D01*
X524926Y48163D01*
X521972Y53678D01*
X521975Y53679D01*
X521904Y53838D01*
G02X526321Y56006I2247J1006D01*
G01X526415Y55830D01*
X526423Y55834D01*
X529283Y50498D01*
X529278Y50493D01*
X529337Y50366D01*
G02X525035Y47998I-2234J-1034D01*
G37*
G36*
G01X535180Y56005D02*
X538116Y50523D01*
X538117Y50522D01*
G02X533792Y48169I-2155J-1191D01*
G01X530840Y53681D01*
G02X535180Y56005I2170J1162D01*
G37*
G36*
G01X533893Y62959D02*
X533786Y63125D01*
X533784Y63124D01*
X530831Y68636D01*
X530836Y68641D01*
X530777Y68768D01*
G02X535180Y70966I2233J1035D01*
G01X535274Y70790D01*
X535282Y70794D01*
X538141Y65457D01*
X538138Y65456D01*
X538209Y65297D01*
G02X533893Y62959I-2248J-1004D01*
G37*
G36*
G01X360545Y730825D02*
X360662Y730965D01*
X360661Y730966D01*
X362924Y733230D01*
X362937D01*
X362995Y733283D01*
G02X365900Y730514I1360J-1482D01*
G01X365783Y730374D01*
X365784Y730373D01*
X363519Y728108D01*
X363518Y728109D01*
X363378Y727992D01*
G02X360545Y730825I-1287J1546D01*
G37*
G36*
G01X370914Y40157D02*
G02X365945Y35188I-4969J0D01*
G01X356102D01*
G02X351132Y40157I0J4970D01*
G01Y71654D01*
G02X356102Y76624I4970J0D01*
G01X365945D01*
G02X370914Y71654I-1J-4970D01*
G01Y40157D01*
G37*
G36*
G01X1162654Y139999D02*
G02X1161307Y136494I-1347J-1494D01*
G01X1158554D01*
X1119811Y97750D01*
X916189D01*
X912250Y101689D01*
Y114701D01*
G02Y117583I1530J1441D01*
G01Y118638D01*
G02Y121520I1530J1441D01*
G01Y122575D01*
G02X911798Y124717I1530J1442D01*
G03X911421Y125250I-377J133D01*
G01X847689D01*
X836250Y136689D01*
Y162189D01*
X830689Y167750D01*
X767198D01*
G02X763960I-1619J1492D01*
G01X762861D01*
G02X759623I-1619J1492D01*
G01X715689D01*
X700750Y182689D01*
Y241106D01*
X699606Y242250D01*
X645189D01*
X640750Y246689D01*
Y278311D01*
X642689Y280250D01*
X699266D01*
X700750Y281734D01*
Y286311D01*
X704326Y289887D01*
X704294Y289999D01*
G02X707501Y293206I2506J701D01*
G01X707613Y293174D01*
X707689Y293250D01*
X712993D01*
G02X715607I1307J-2250D01*
G01X717493D01*
G02X720107I1307J-2250D01*
G01X721993D01*
G02X724607I1307J-2250D01*
G01X726493D01*
G02X729107I1307J-2250D01*
G01X730993D01*
G02X733607I1307J-2250D01*
G01X735993D01*
G02X738607I1307J-2250D01*
G01X777506D01*
G02X802194I12344J-9786D01*
G01X979311D01*
X981811Y290750D01*
X1217811D01*
X1221750Y286811D01*
Y271769D01*
X1223269Y270250D01*
X1280811D01*
X1283250Y267811D01*
Y219689D01*
X1279311Y215750D01*
X1223114D01*
X1221750Y214386D01*
Y199689D01*
X1162639Y140579D01*
G03X1162654Y139999I283J-283D01*
G37*
G36*
G01X311916Y203241D02*
X311817Y203256D01*
X299430Y190869D01*
Y189241D01*
X300421Y188250D01*
X426347D01*
X478020Y136577D01*
Y81541D01*
X535811Y23750D01*
X686789D01*
X735379Y72340D01*
X794421D01*
X807411Y59350D01*
X877111D01*
X877811Y58650D01*
X927089D01*
X939189Y70750D01*
X958824D01*
X958844Y70754D01*
G02X959756I456J-2154D01*
G01X959776Y70750D01*
X1041389D01*
X1050389Y79750D01*
X1074111D01*
X1080950Y72911D01*
Y47689D01*
X1075650Y42389D01*
Y27911D01*
X1078750Y24811D01*
Y-10511D01*
X1076511Y-12750D01*
X1008689D01*
X1004689Y-8750D01*
X973511D01*
X969511Y-12750D01*
X511189D01*
X412189Y86250D01*
X381689D01*
X354019Y113920D01*
X216019D01*
X178364Y151575D01*
X171985D01*
X149727Y173833D01*
X149631Y173822D01*
G02X147192Y176261I-251J2188D01*
G01X147203Y176357D01*
X121618Y201942D01*
Y208321D01*
X116689Y213250D01*
X93811D01*
X93411Y212851D01*
G03X93413Y212283I283J-283D01*
G02X92000Y208840I-1413J-1432D01*
G01X88799D01*
G02X87494Y209321I0J2011D01*
G03X87217Y209305I-130J-152D01*
G02X83410Y210571I-1617J1495D01*
G01X83391Y210750D01*
X61736D01*
G02X58147Y210345I-1936J1050D01*
G03X57870Y210368I-150J-132D01*
G02X56600Y209916I-1271J1560D01*
G01X53399D01*
G02X52036Y210450I2J2012D01*
G03X51758Y210444I-136J-147D01*
G02X48387Y210750I-1558J1556D01*
G01X24189D01*
X8250Y226689D01*
Y668311D01*
X45337Y705398D01*
X45351Y705425D01*
G02X46275Y706349I1949J-1025D01*
G01X46302Y706363D01*
X88189Y748250D01*
X98923D01*
X99750Y749077D01*
Y787811D01*
X102189Y790250D01*
X219811D01*
X232131Y777930D01*
X232250Y777973D01*
G02X235070Y775153I750J-2070D01*
G01X235027Y775034D01*
X263630Y746431D01*
X263657Y746417D01*
G02X264589Y745472I-1029J-1947D01*
G01X264811Y745250D01*
X340811D01*
X521311Y564750D01*
X1322811D01*
X1391750Y495811D01*
Y188689D01*
X1387311Y184250D01*
X1367792D01*
G02X1363816I-1988J947D01*
G01X1362189D01*
X1357750Y188689D01*
Y273481D01*
G02Y277489I912J2004D01*
G01Y472189D01*
X1301689Y528250D01*
X1008261D01*
X1008220Y528104D01*
G02X1003980I-2120J596D01*
G01X1003939Y528250D01*
X560311D01*
X557750Y525689D01*
Y359813D01*
G02Y356187I-1250J-1813D01*
G01Y334911D01*
X565650Y327011D01*
Y308389D01*
X559011Y301750D01*
X442811D01*
X378811Y237750D01*
X346311D01*
X316444Y207883D01*
X316459Y207784D01*
G02X311916Y203241I-3959J-584D01*
G37*
G54D50*
X1075197Y92126D03*
G54D49*
X526215Y184000D03*
X565585D03*
G54D51*
X1301120Y173278D03*
Y183908D03*
G54D48*
X487405Y255240D03*
G54D41*
X16200Y120100D03*
X27200Y821800D03*
X1384200Y122800D03*
X1373200Y823500D03*
G54D42*
X26977Y151614D03*
X96189D03*
G54D46*
X336417Y21260D03*
G54D44*
X42587Y151614D03*
X80579D03*
G54D43*
X39370Y801181D03*
X1360630Y135826D03*
Y801181D03*
G54D45*
X293110Y55906D03*
G54D52*
X1333661Y55905D03*
X1376968Y21259D03*
Y90551D03*
G54D47*
X336417D03*
%LPC*%
G75*
G36*
G01X87352Y212250D02*
X86982D01*
X86926Y212300D01*
G03X84220Y212250I-1326J-1500D01*
G01X61961D01*
X61920Y212396D01*
G03X58268Y213382I-2120J-596D01*
G02X57991Y213381I-139J144D01*
G03X56600Y213940I-1392J-1453D01*
G01X53400D01*
G03X52093Y213457I1J-2012D01*
G02X51561Y213468I-260J304D01*
G03X48240Y212409I-1361J-1468D01*
G01X48207Y212250D01*
X24811D01*
X9750Y227311D01*
Y667689D01*
X88811Y746750D01*
X117189D01*
X204689Y659250D01*
X288689D01*
X337750Y610189D01*
Y348311D01*
X298689Y309250D01*
X271886D01*
G03X267812I-2037J-836D01*
G01X128189D01*
X117750Y298811D01*
Y275689D01*
X204368Y189071D01*
X204341Y188963D01*
G03X206296Y186480I1956J-471D01*
G01X206958D01*
X212689Y180750D01*
X240404D01*
X240432Y180582D01*
G03X245568I2568J418D01*
G01X245596Y180750D01*
X289311D01*
X296741Y188180D01*
X298369D01*
X299799Y186750D01*
X425725D01*
X476520Y135955D01*
Y80919D01*
X535189Y22250D01*
X687411D01*
X736001Y70840D01*
X793799D01*
X806789Y57850D01*
X876489D01*
X877189Y57150D01*
X927711D01*
X939811Y69250D01*
X1042011D01*
X1051011Y78250D01*
X1073489D01*
X1079450Y72289D01*
Y48311D01*
X1074150Y43011D01*
Y27289D01*
X1077250Y24189D01*
Y-9889D01*
X1075889Y-11250D01*
X1057541D01*
G02X1057193Y-10653I0J400D01*
G03X1051795I-2699J1528D01*
G02X1051447Y-11250I-348J-197D01*
G01X1030769D01*
G02X1030421Y-10653I0J400D01*
G03X1025023I-2699J1528D01*
G02X1024675Y-11250I-348J-197D01*
G01X1009311D01*
X1005311Y-7250D01*
X972889D01*
X968889Y-11250D01*
X511811D01*
X412811Y87750D01*
X382311D01*
X354641Y115420D01*
X216641D01*
X178986Y153075D01*
X172607D01*
X151076Y174606D01*
G03X148109Y177808I-1696J1404D01*
G01X147971Y177711D01*
X123118Y202564D01*
Y208943D01*
X117311Y214750D01*
X93189D01*
X91302Y212862D01*
X88799D01*
G03X87410Y212305I0J-2011D01*
G01X87352Y212250D01*
G37*
G36*
G01X102811Y788750D02*
X219189D01*
X231034Y776905D01*
X230980Y776780D01*
G03X230902Y775233I2020J-877D01*
G02X230521Y774712I-381J-121D01*
G01X228550D01*
G03X228549Y770688I0J-2012D01*
G01X231750D01*
G03X233645Y773376I0J2012D01*
G02X233864Y773878I377J134D01*
G03X233877Y773883I-784J2058D01*
G01X234002Y773937D01*
X264189Y743750D01*
X340189D01*
X357480Y726459D01*
G03X358624Y725315I2020J876D01*
G01X520689Y563250D01*
X1322189D01*
X1390250Y495189D01*
Y189311D01*
X1386689Y185750D01*
X1383628D01*
G03X1380648I-1490J-1621D01*
G01X1367940D01*
X1367895Y185887D01*
G03X1363713I-2091J-690D01*
G01X1363668Y185750D01*
X1362811D01*
X1359250Y189311D01*
Y273358D01*
X1359384Y273405D01*
G03Y277565I-722J2080D01*
G01X1359250Y277612D01*
Y472811D01*
X1302311Y529750D01*
X1008036D01*
G03X1004164I-1936J-1050D01*
G01X559689D01*
X556250Y526311D01*
Y360194D01*
X556087Y360163D01*
G03Y355837I413J-2163D01*
G01X556250Y355806D01*
Y334289D01*
X564150Y326389D01*
Y309011D01*
X558389Y303250D01*
X442189D01*
X378189Y239250D01*
X345689D01*
X288689Y182250D01*
X245282D01*
G03X240718I-2282J-1250D01*
G01X213311D01*
X209422Y186139D01*
G02X209563Y186480I141J141D01*
G01X209866D01*
G03Y190504I0J2012D01*
G01X206297D01*
G03X205314Y190247I1J-2012D01*
G01X119250Y276311D01*
Y298189D01*
X128811Y307750D01*
X267745D01*
X267794Y307622D01*
G03X271904I2055J792D01*
G01X271953Y307750D01*
X299311D01*
X339250Y347689D01*
Y610811D01*
X289311Y660750D01*
X205311D01*
X117811Y748250D01*
X101917D01*
X101250Y748917D01*
Y787189D01*
X102811Y788750D01*
G37*
G36*
G01X699236Y243750D02*
X645811D01*
X642250Y247311D01*
Y277689D01*
X643311Y278750D01*
X699436D01*
X700750Y277436D01*
Y245264D01*
X699236Y243750D01*
G37*
G36*
G01X848311Y126750D02*
X837750Y137311D01*
Y162811D01*
X831311Y169250D01*
X767789D01*
X767773Y169433D01*
G03X763744Y170459I-2194J-191D01*
G02X763077I-333J221D01*
G03X759048Y169433I-1835J-1217D01*
G01X759032Y169250D01*
X716311D01*
X702250Y183311D01*
Y285689D01*
X705201Y288640D01*
X705338Y288547D01*
G03X709340Y291263I1462J2153D01*
G02X709731Y291750I391J87D01*
G01X775753D01*
G02X776103Y291155I1J-400D01*
G03X803597I13747J-7691D01*
G02X803947Y291750I349J195D01*
G01X978689D01*
X981189Y289250D01*
X1003786D01*
X1005250Y287786D01*
Y218611D01*
X1003889Y217250D01*
X923189D01*
X922453Y216514D01*
X922335Y216555D01*
G03X919665Y213885I-681J-1989D01*
G01X919706Y213767D01*
X918516Y212577D01*
X918398Y212618D01*
G03X915728Y209948I-681J-1989D01*
G01X915769Y209830D01*
X914750Y208811D01*
Y161689D01*
X915909Y160530D01*
X915843Y160401D01*
G03X918669Y157575I1874J-952D01*
G01X918798Y157641D01*
X919750Y156689D01*
Y156404D01*
X919733Y156365D01*
G03Y154659I1921J-853D01*
G01X919750Y154620D01*
Y152467D01*
X919733Y152428D01*
G03Y150722I1921J-853D01*
G01X919750Y150683D01*
Y148530D01*
X919733Y148491D01*
G03Y146785I1921J-853D01*
G01X919750Y146746D01*
Y140656D01*
X919733Y140617D01*
G03Y138911I1921J-853D01*
G01X919750Y138872D01*
Y136719D01*
X919733Y136680D01*
G03Y134974I1921J-853D01*
G01X919750Y134935D01*
Y133811D01*
X912689Y126750D01*
X848311D01*
G37*
G36*
G01X1158107Y140516D02*
G03X1156710Y137058I0J-2011D01*
G02X1156712Y136773I-139J-143D01*
G01X1119189Y99250D01*
X950837D01*
G03X948163I-1337J-1750D01*
G01X936194D01*
G03X933806I-1194J-1850D01*
G01X916811D01*
X913750Y102311D01*
Y125689D01*
X913915Y125854D01*
X913986Y125861D01*
G03X915872Y127747I-206J2092D01*
G01X915879Y127818D01*
X917852Y129791D01*
X917923Y129798D01*
G03X919809Y131684I-206J2092D01*
G01X919816Y131755D01*
X921250Y133189D01*
Y157311D01*
X919729Y158832D01*
X919757Y158941D01*
G03X917209Y161489I-2040J508D01*
G01X917100Y161461D01*
X916250Y162311D01*
Y208189D01*
X916796Y208735D01*
X916919Y208684D01*
G03X919662Y211427I798J1945D01*
G01X919611Y211550D01*
X920733Y212672D01*
X920856Y212621D01*
G03X923599Y215364I798J1945D01*
G01X923548Y215487D01*
X923811Y215750D01*
X1004511D01*
X1005558Y216797D01*
X1005570Y216806D01*
G03X1006036Y217275I-1239J1698D01*
G01X1006750Y217989D01*
Y287776D01*
X1008224Y289250D01*
X1217189D01*
X1220250Y286189D01*
Y200311D01*
X1160456Y140516D01*
X1158107D01*
G37*
G36*
G01X1278689Y217250D02*
X1223444D01*
X1221750Y218944D01*
Y267261D01*
X1223239Y268750D01*
X1280189D01*
X1281750Y267189D01*
Y220311D01*
X1278689Y217250D01*
G37*
%LPD*%
G75*
G36*
G01X115226Y418475D02*
X115233Y418468D01*
X112119Y415354D01*
X112115D01*
X112113Y415356D01*
X112107D01*
G02X108619Y418688I-1701J1711D01*
G01X108694Y418775D01*
X108691Y418778D01*
X111807Y421894D01*
X111810Y421891D01*
X111897Y421966D01*
G02X115226Y418475I1621J-1787D01*
G37*
G36*
G01X1069124Y57175D02*
Y60376D01*
G02X1073146Y60375I2011J-1D01*
G01Y57175D01*
G02X1069124I-2011J0D01*
G37*
G36*
G01X1059012Y57700D02*
Y54499D01*
G02X1054988Y54500I-2012J1D01*
G01Y57700D01*
G02X1059012I2012J0D01*
G37*
G36*
G01X1063212Y24088D02*
Y20887D01*
G02X1059188Y20888I-2012J1D01*
G01Y24088D01*
G02X1063212I2012J0D01*
G37*
G36*
G01X1067712Y36088D02*
Y32887D01*
G02X1063688Y32888I-2012J1D01*
G01Y36088D01*
G02X1067712I2012J0D01*
G37*
G36*
G01X728620Y49251D02*
Y46050D01*
G02X724598Y46051I-2011J1D01*
G01Y49251D01*
G02X728620I2011J0D01*
G37*
G36*
G01X722955Y35106D02*
X726156D01*
G02X726155Y31084I-1J-2011D01*
G01X722955D01*
G02Y35106I0J2011D01*
G37*
G36*
G01X401588Y142542D02*
Y146043D01*
G02X405612Y146042I2012J-1D01*
G01Y142542D01*
G02X401588I-2012J0D01*
G37*
G36*
G01X403312Y156715D02*
Y153214D01*
G02X399288Y153215I-2012J1D01*
G01Y156715D01*
G02X403312I2012J0D01*
G37*
G36*
G01X260407Y500662D02*
X257206D01*
G02X257207Y504686I1J2012D01*
G01X260407D01*
G02Y500662I0J-2012D01*
G37*
G36*
G01X223872Y339875D02*
Y335474D01*
G02X219048Y335475I-2412J1D01*
G01Y339875D01*
G02X223872I2412J0D01*
G37*
G36*
G01X105282Y565740D02*
Y561339D01*
G02X100458Y561340I-2412J1D01*
G01Y565740D01*
G02X105282I2412J0D01*
G37*
G36*
G01X93612Y453200D02*
Y448799D01*
G02X88788Y448800I-2412J1D01*
G01Y453200D01*
G02X93612I2412J0D01*
G37*
G36*
G01X93940Y438600D02*
Y443001D01*
G02X98762Y443000I2411J-1D01*
G01Y438600D01*
G02X93940I-2411J0D01*
G37*
G36*
G01X83500Y342188D02*
X80299D01*
G02X80300Y346212I1J2012D01*
G01X83500D01*
G02Y342188I0J-2012D01*
G37*
G36*
G01X77421Y320458D02*
X74220D01*
G02X74221Y324482I1J2012D01*
G01X77421D01*
G02Y320458I0J-2012D01*
G37*
G36*
G01X76325Y286220D02*
X73124D01*
G02X73125Y290242I1J2011D01*
G01X76325D01*
G02Y286220I0J-2011D01*
G37*
G36*
G01X74200Y218540D02*
X77401D01*
G02X77400Y214516I-1J-2012D01*
G01X74200D01*
G02Y218540I0J2012D01*
G37*
G36*
G01X65400Y286244D02*
X62199D01*
G02X62200Y290268I1J2012D01*
G01X65400D01*
G02Y286244I0J-2012D01*
G37*
G36*
G01X65712Y263925D02*
Y260724D01*
G02X61688Y260725I-2012J1D01*
G01Y263925D01*
G02X65712I2012J0D01*
G37*
G36*
G01X57812Y269493D02*
Y266292D01*
G02X53788Y266293I-2012J1D01*
G01Y269493D01*
G02X57812I2012J0D01*
G37*
G36*
G01X38050Y218740D02*
X41251D01*
G02X41250Y214716I-1J-2012D01*
G01X38050D01*
G02Y218740I0J2012D01*
G37*
G36*
G01X401628Y323300D02*
G02X406452I2412J0D01*
G01Y318899D01*
G02X401628Y318900I-2412J1D01*
G01Y323300D01*
G37*
G36*
G01X343664Y301534D02*
G02X339640I-2012J0D01*
G01Y305035D01*
G02X343664Y305034I2012J-1D01*
G01Y301534D01*
G37*
G36*
G01X802200Y198010D02*
G02Y193990I0J-2010D01*
G01X798999D01*
G02X799000Y198010I1J2010D01*
G01X802200D01*
G37*
G36*
G01X776396Y183890D02*
G02X781218I2411J0D01*
G01Y179489D01*
G02X776396Y179490I-2411J1D01*
G01Y183890D01*
G37*
G36*
G01X787586Y193393D02*
G02X787614Y198215I14J2411D01*
G01X792013Y198189D01*
G02X791986Y193367I-14J-2411D01*
G01X787586Y193393D01*
G37*
G36*
G01X795172Y176043D02*
G02X790348I-2412J0D01*
G01Y180444D01*
G02X795172Y180443I2412J-1D01*
G01Y176043D01*
G37*
G36*
G01X1141901Y139861D02*
G02X1141900Y135841I-1J-2010D01*
G01X1138700D01*
G02Y139861I0J2010D01*
G01X1141901D01*
G37*
G36*
G01X1124012Y130124D02*
G02X1119990I-2011J0D01*
G01Y133325D01*
G02X1124012Y133324I2011J-1D01*
G01Y130124D01*
G37*
G54D50*
X988040Y3984D03*
X1013630D03*
G54D51*
X92990Y252362D03*
X116790D03*
G54D52*
X789850Y236220D03*
G54D54*
X75800Y229289D03*
G54D53*
X90459Y223184D03*
X64600Y342700D03*
G54D55*
X54378Y237402D03*
G54D38*
X1348785Y179358D03*
X1323195D03*
G54D14*
X23100Y224500D03*
X28400Y262800D03*
X18000Y271600D03*
X26600Y249217D03*
Y253582D03*
X18000Y289400D03*
X28200Y296100D03*
X26300Y317600D03*
X21400Y327900D03*
Y341000D03*
Y354000D03*
X22900Y365300D03*
X31324Y410800D03*
X25350Y389000D03*
X17500Y412374D03*
X20713Y410087D03*
Y418326D03*
X23720Y472640D03*
X29300Y539850D03*
X24800Y540900D03*
X26100Y671200D03*
X24000Y659000D03*
X29500Y676500D03*
X25200Y712650D03*
X17500Y706300D03*
X21300Y728400D03*
X21108Y732713D03*
X21250Y742650D03*
X27000Y754400D03*
X44400Y216600D03*
X34900Y216800D03*
X59800Y211800D03*
X50200Y212000D03*
X31500Y224400D03*
X41250Y216728D03*
X53400Y211928D03*
X38050Y216728D03*
X56600Y211928D03*
X58400Y271800D03*
X57500Y263300D03*
X63700Y257300D03*
X63800Y267100D03*
X44029Y272572D03*
X44426Y267408D03*
X35150Y273250D03*
X60872Y274328D03*
X63700Y260725D03*
X55800Y266293D03*
X63700Y263925D03*
X55800Y269493D03*
X44900Y261750D03*
X35300Y303100D03*
X59173Y288186D03*
X42900Y284500D03*
X58730Y299508D03*
X35150Y284350D03*
X39000Y299500D03*
X53100Y279500D03*
X47800Y309400D03*
X31662Y303262D03*
X58700Y308600D03*
X61800Y306900D03*
X38800Y302900D03*
X62200Y288256D03*
X58383Y294947D03*
X47355Y303376D03*
X47991Y299958D03*
X49934Y280811D03*
X49100Y328300D03*
X39600Y317600D03*
X58990Y342700D03*
X34800Y321200D03*
X54600Y328600D03*
X31700Y314700D03*
X52050Y316100D03*
X51050Y321650D03*
X62400Y342700D03*
X38518Y376916D03*
X34153D03*
X39866Y371366D03*
X52521Y350357D03*
X31500Y366900D03*
X48512Y356488D03*
X49300Y346700D03*
X43262Y357062D03*
X44866Y378634D03*
X55907Y350673D03*
X54200Y347400D03*
X63500Y353960D03*
X62838Y392392D03*
X60610Y381665D03*
X47132Y444399D03*
X48000Y426000D03*
Y422500D03*
Y429500D03*
X57800Y420700D03*
X35709Y426942D03*
X43500Y418802D03*
X47734Y465792D03*
X45531Y474400D03*
X31500Y447000D03*
X64820Y455887D03*
X64680Y452389D03*
X64500Y459400D03*
X49812Y479921D03*
X33900Y469300D03*
X46500Y460300D03*
X46087Y455819D03*
X50140Y494559D03*
X60987Y489223D03*
X60150Y506450D03*
X50140Y490750D03*
X60900Y495122D03*
X61870Y515670D03*
X60300Y533900D03*
X61128Y519646D03*
X64200Y534500D03*
X61800Y537000D03*
X55950Y564500D03*
X63000Y558930D03*
X62611Y608289D03*
X62400Y624500D03*
X53000Y645000D03*
X63300Y634800D03*
X43600Y665700D03*
X54200Y666800D03*
X60700Y682100D03*
X47800Y666400D03*
X35766Y673178D03*
X34500Y666500D03*
X39900Y678100D03*
X33600Y675800D03*
X43100Y670900D03*
X36624Y669155D03*
X47300Y704400D03*
X42300Y704900D03*
X62000Y713000D03*
X45800Y685100D03*
X42100Y684000D03*
X53500Y690200D03*
X60650Y694050D03*
X63300Y697200D03*
X59100Y705600D03*
X42130Y694440D03*
X38000Y684000D03*
X59300Y734900D03*
X54300Y729900D03*
X49300Y734900D03*
X54300Y739900D03*
Y734900D03*
X56590Y720410D03*
X47800Y772900D03*
X35000Y769900D03*
X39000D03*
X42800Y770000D03*
X52500Y779600D03*
X64900Y780500D03*
X92859Y226659D03*
X87978Y226596D03*
X78508Y232693D03*
X72934Y232675D03*
X85600Y210800D03*
X80600Y216700D03*
X71000Y216600D03*
X88276Y232700D03*
X88259Y223184D03*
X92659D03*
X78000Y229289D03*
X73600D03*
X77400Y216528D03*
X88800Y210851D03*
X74200Y216528D03*
X92000Y210851D03*
X97480Y266420D03*
X94600Y277100D03*
X93672Y270153D03*
X71870Y257120D03*
X75800Y274100D03*
X68100Y255000D03*
X71094Y285981D03*
X77964Y285670D03*
X68429Y288212D03*
X75400Y309700D03*
X71500Y297900D03*
X77100Y303800D03*
X65400D03*
X65500Y291900D03*
X77500D03*
X96798Y301484D03*
Y297915D03*
X95700Y293900D03*
X73125Y288231D03*
X76325D03*
X65400Y288256D03*
X84600Y303000D03*
X78121Y325870D03*
X73721D03*
X70210Y342700D03*
X77290Y344212D03*
X86511Y344200D03*
X66400Y334500D03*
X66800Y342700D03*
X83500Y344200D03*
X80300D03*
X77421Y322470D03*
X74221D03*
X79455Y357174D03*
X75256Y370303D03*
X70591Y359309D03*
X71794Y377639D03*
X82500Y362890D03*
X92580Y410761D03*
X79600Y399200D03*
X95223Y385704D03*
X86904Y385798D03*
X72708Y382055D03*
X68365Y381464D03*
X84700Y396000D03*
X92752Y434193D03*
X91370Y445394D03*
X70700Y443244D03*
X77859Y429879D03*
X72533Y416996D03*
X79164Y426221D03*
X96351Y443000D03*
Y438600D03*
X85042Y439144D03*
X91200Y448800D03*
Y453200D03*
X91311Y456609D03*
X89400Y470400D03*
X89500Y466600D03*
X73232Y476912D03*
X97100Y466500D03*
X98400Y454400D03*
X77681Y499033D03*
X77413Y506468D03*
X70910Y502219D03*
X67700Y499120D03*
X77700Y522500D03*
X67700Y518500D03*
X67162Y515142D03*
X77300Y531238D03*
X77700Y538500D03*
X74301Y538390D03*
X65800Y538900D03*
X74300Y533600D03*
X73900Y527050D03*
X77372Y526885D03*
X73700Y542600D03*
X70000Y542500D03*
X74000Y557000D03*
X77500Y554500D03*
X90500Y580100D03*
X81000Y579000D03*
X95252Y571638D03*
X70800Y559895D03*
X77400Y559000D03*
X77250Y562750D03*
X77400Y577000D03*
X71400Y578300D03*
X87555Y561085D03*
X87200Y574250D03*
X87337Y569268D03*
X84226Y577924D03*
X87200Y565785D03*
X77400Y550400D03*
X65381Y548719D03*
X87608Y557685D03*
X69100Y549200D03*
X73700Y549300D03*
X92000Y591200D03*
X69500Y586000D03*
X90500Y587000D03*
X80300Y596100D03*
X69258Y603000D03*
X82000Y592500D03*
X66000Y604800D03*
X78300Y634250D03*
X94860Y628750D03*
X75800Y681900D03*
X94950Y677850D03*
X75450Y694150D03*
X69700Y690300D03*
X89825Y692875D03*
X79250Y716050D03*
X91800Y716100D03*
X66700Y713500D03*
X74500Y713400D03*
X91450Y707650D03*
X65350Y690356D03*
X89400Y749200D03*
X89300Y736300D03*
X95400Y731600D03*
Y728200D03*
X68900Y730000D03*
X68465Y736229D03*
X85800Y727500D03*
Y731000D03*
X74300Y769950D03*
X89800Y753400D03*
X69800Y772700D03*
X86900Y757900D03*
X89400Y762400D03*
X93100Y813200D03*
X93300Y818900D03*
X108631Y168836D03*
X111967Y199632D03*
X119800Y234531D03*
X103100Y211600D03*
X127330Y248029D03*
X112764Y264218D03*
X107340Y266140D03*
X101463Y268811D03*
X102499Y281183D03*
X109810Y310358D03*
X109972Y305968D03*
X112217Y296435D03*
X120700Y282400D03*
X100500Y285300D03*
X113915Y307600D03*
X117484D03*
X106400Y312200D03*
X117700Y323400D03*
X111900Y344200D03*
X113000Y336000D03*
X107558Y321012D03*
X122000Y343300D03*
X100277Y336077D03*
X102000Y364700D03*
X99128Y366961D03*
X108200Y378656D03*
X126800Y362500D03*
X108484Y348377D03*
X117300Y361700D03*
X108453Y385164D03*
X100924Y409968D03*
X124290Y401910D03*
X125718Y383302D03*
X125600Y386700D03*
X107358Y409942D03*
X126122Y432323D03*
X105303Y419497D03*
X116173Y422379D03*
X107844Y414785D03*
X99749Y443671D03*
X99818Y437908D03*
X127925Y428093D03*
X110406Y417067D03*
X113518Y420179D03*
X131304Y418855D03*
X131004Y422710D03*
X130633Y444763D03*
X120200Y436400D03*
X115500Y454700D03*
X111500D03*
X103500D03*
X120000Y451285D03*
X107900Y448900D03*
X101200Y470400D03*
X129520Y448660D03*
X127820Y452280D03*
X123696Y454452D03*
X114400Y550000D03*
X104461Y571715D03*
X100140Y559260D03*
X99460Y566200D03*
X102870Y565740D03*
Y561340D03*
X105851Y611436D03*
X104400Y590300D03*
X102000Y599000D03*
X120351Y633500D03*
X126851Y633449D03*
X116551Y644936D03*
X128220Y620392D03*
X125581Y641436D03*
X131051Y656436D03*
X119051Y653906D03*
X109800Y681900D03*
X130900Y714300D03*
Y710800D03*
X107950Y687650D03*
X111400Y741800D03*
Y718300D03*
X118060Y743460D03*
X107000Y717800D03*
X132200Y761300D03*
Y756300D03*
X111300Y756000D03*
X149380Y176010D03*
X163000Y211500D03*
X157200Y241400D03*
X153000Y225000D03*
X155026Y212580D03*
X134120Y267630D03*
X157300Y259900D03*
X157400Y254000D03*
X157300Y246500D03*
X155662Y266438D03*
X159662Y266600D03*
X162910Y244290D03*
X139286Y311214D03*
X166087Y304350D03*
X143000Y342900D03*
X155891Y339730D03*
X134800Y329600D03*
X144595Y312861D03*
X137862Y361723D03*
X161311Y371428D03*
X141216Y361163D03*
X145027D03*
X156573Y371799D03*
X140500Y390500D03*
X145500Y385500D03*
X158800Y406255D03*
X143000Y388000D03*
X142608Y403594D03*
X157550Y399100D03*
X155657Y384291D03*
X137000Y436700D03*
X145901Y441262D03*
X139019Y443177D03*
X159540Y445692D03*
X146165Y444876D03*
X149838Y446190D03*
X150431Y420306D03*
X153100Y439000D03*
X136500Y417400D03*
X152978Y435602D03*
X137344Y446737D03*
X137000Y451300D03*
X163440Y453020D03*
X133000Y454700D03*
X143547Y477976D03*
X159239Y449079D03*
X159082Y452509D03*
X165851Y630651D03*
X137551Y629849D03*
X149851Y631251D03*
X155851Y631051D03*
X160851Y630651D03*
X150069Y640500D03*
X150280Y636620D03*
X150600Y648300D03*
X150409Y643884D03*
X153019Y622720D03*
X159716Y620392D03*
X166015D03*
X136651Y653036D03*
X162100Y677800D03*
X164400Y668300D03*
X164500Y693500D03*
X144400Y731600D03*
Y728200D03*
X136400Y738300D03*
Y721800D03*
X161200Y723900D03*
X150200Y729400D03*
X153700D03*
X157700Y748900D03*
X150450Y744150D03*
X146450Y736150D03*
X135700Y745200D03*
X163800Y771000D03*
X160400D03*
X154000Y779000D03*
X160700Y753400D03*
X143000Y784500D03*
X146500D03*
X139250Y791250D03*
X143250Y799250D03*
X153500Y808500D03*
X163800Y820000D03*
X160400D03*
X171500Y207500D03*
Y202500D03*
X193400Y192900D03*
X196018Y204200D03*
X167000Y211500D03*
X172450Y211050D03*
X183400Y221600D03*
X171100Y247500D03*
X191000Y246500D03*
X167600Y247600D03*
X193303Y264310D03*
X167700Y296882D03*
Y292517D03*
X180850Y285650D03*
X170062Y304556D03*
X174943Y321015D03*
X167687Y329434D03*
X192407Y320262D03*
X180571Y327023D03*
X176674Y344934D03*
X189365Y329905D03*
X179381Y369903D03*
X196529Y352284D03*
X185970Y358962D03*
X195940Y348814D03*
X182969Y352641D03*
X192150Y406429D03*
X197000Y404000D03*
X171434Y398093D03*
X166321Y388316D03*
X176098Y444355D03*
X185000Y419900D03*
X197531Y451187D03*
X189381Y451394D03*
X193718D03*
X196239Y462262D03*
X173471Y454700D03*
X177500Y454300D03*
X199900Y544500D03*
X196782Y563564D03*
X197334Y567232D03*
X197500Y577300D03*
X189500Y567700D03*
X184189Y564504D03*
X185500Y567700D03*
X193001Y574708D03*
X181000Y585000D03*
Y581500D03*
X198600Y599750D03*
Y588750D03*
X181371Y601636D03*
X181000Y595200D03*
X168769Y622720D03*
X171300Y678300D03*
X175200Y678500D03*
X199900Y692000D03*
X171000Y715900D03*
X167600D03*
X193500Y700000D03*
X182500Y705500D03*
X186000D03*
X178750Y712250D03*
X189000Y684500D03*
X185000D03*
X167000Y686500D03*
X199900Y747500D03*
Y741000D03*
X190000Y725000D03*
X177700Y723900D03*
X182860Y742240D03*
X181200Y748900D03*
X184700Y729400D03*
X182750Y720250D03*
X193000Y729500D03*
X171000Y764900D03*
X167600D03*
X190000Y780500D03*
X170500Y779000D03*
X193500Y755500D03*
X182500Y761000D03*
X186000D03*
X182750Y775750D03*
X178000Y753400D03*
X178750Y767750D03*
X199900Y796500D03*
X177500Y784500D03*
X170800Y808500D03*
X193000Y785000D03*
X197420Y821701D03*
X194120Y830301D03*
X190920D03*
X176900Y867600D03*
X173500D03*
X197218Y871676D03*
X228163Y68589D03*
X222354Y103006D03*
X228163Y78589D03*
X227606Y98642D03*
X223641Y99302D03*
X228163Y93589D03*
Y88589D03*
X228500Y138100D03*
X223750Y141370D03*
X218725Y138175D03*
X233500Y137000D03*
X220300Y129300D03*
X222356Y133438D03*
X228708Y127115D03*
X215136Y142786D03*
X218299Y123319D03*
X224576Y116678D03*
X221418Y109634D03*
X210478Y151203D03*
X213282Y188452D03*
X202892Y188441D03*
X205013Y192596D03*
X206297Y188492D03*
X209866D03*
X214794Y212100D03*
X206200Y247500D03*
X209200Y252800D03*
X230400Y283400D03*
X222200Y300500D03*
X205840Y325381D03*
X210177D03*
X218102Y334880D03*
X218070Y340244D03*
X221460Y335475D03*
Y339875D03*
X228100Y364600D03*
X219018Y378000D03*
X223383D03*
X217000Y360000D03*
X219580Y356970D03*
X214776Y352807D03*
X212536Y349805D03*
X205915Y422424D03*
X217190Y428485D03*
X212200Y428800D03*
X212000Y438713D03*
X217500Y441992D03*
X200100Y415100D03*
X201868Y451187D03*
X227700Y476537D03*
Y472200D03*
X216404Y469751D03*
X216282Y463288D03*
X219763Y472187D03*
X228900Y446800D03*
X219300Y508700D03*
X228298Y488100D03*
X228347Y484700D03*
X219700Y489800D03*
X202700Y495400D03*
X206700Y498000D03*
X216600Y496550D03*
X217800Y512500D03*
X200917Y490578D03*
X203550Y484522D03*
X233290Y493277D03*
X206700Y494000D03*
X203500Y499200D03*
X207026Y483956D03*
X226300Y505700D03*
X226530Y502307D03*
X216873Y516458D03*
X203300Y538500D03*
X206700Y544500D03*
Y538500D03*
X221000Y541300D03*
X217500Y519800D03*
Y529250D03*
X225000Y541300D03*
X229200Y514800D03*
X203300Y544500D03*
Y548500D03*
X219700Y550500D03*
X218780Y560082D03*
X206700Y548500D03*
X216300Y550500D03*
X216278Y567341D03*
X202300Y559763D03*
X229800Y558500D03*
X206700Y554500D03*
X203304Y554684D03*
X205700Y559763D03*
X222500Y573220D03*
X216241Y563095D03*
X216090Y593937D03*
X227500Y603500D03*
X201000Y674000D03*
X206952Y655370D03*
X203300Y692000D03*
X219000Y694000D03*
X210000Y700000D03*
X231500Y699000D03*
X217000Y705500D03*
X203300Y747500D03*
Y741000D03*
X213500Y725000D03*
X215160Y718340D03*
X210300Y729500D03*
X227409Y775903D03*
X233000D03*
X213500Y780500D03*
X210000Y755500D03*
X215160Y773840D03*
X217000Y761000D03*
X228550Y772700D03*
X231750D03*
X203300Y796500D03*
X210300Y785000D03*
X200620Y821701D03*
X231915Y830301D03*
X219317D03*
X206718D03*
X228715D03*
X216117D03*
X203518D03*
X225615Y875176D03*
X213017D03*
X200418Y871676D03*
X222415Y875176D03*
X209817D03*
X257759Y68589D03*
X264817Y105350D03*
X257731Y78589D03*
X258100Y93589D03*
X257912Y101408D03*
X258029Y97353D03*
X260562Y85988D03*
X254000Y131500D03*
X264500Y142750D03*
X254500D03*
X246500Y139000D03*
X243000D03*
X258068Y110180D03*
X259331Y118580D03*
X264443Y109587D03*
X257422Y121792D03*
X259500Y143250D03*
Y147750D03*
Y160750D03*
Y156250D03*
X264397Y160977D03*
X264500Y157250D03*
Y153750D03*
Y150250D03*
Y146250D03*
X259500Y152000D03*
X254500Y161250D03*
Y157250D03*
Y153750D03*
Y150250D03*
Y146250D03*
X239600Y142900D03*
X243618Y143381D03*
X243500Y147500D03*
X241231Y238869D03*
X236300Y227280D03*
X247500Y233750D03*
X244300Y226700D03*
X266500Y239400D03*
X245400Y296500D03*
X267300Y300600D03*
Y328640D03*
X257340Y338640D03*
X267300Y362200D03*
X244000Y377617D03*
X260929Y345571D03*
X248930Y358000D03*
X244000Y381982D03*
X258500Y391200D03*
X239100Y399200D03*
X251700Y421600D03*
Y425200D03*
X238400Y416200D03*
X235750Y419500D03*
X264100Y425400D03*
X249342Y439064D03*
X251800Y470100D03*
X248500Y465000D03*
X263700Y474600D03*
X257493Y456679D03*
X253302D03*
X257400Y477300D03*
X246300Y478600D03*
Y485400D03*
X246407Y488799D03*
X256300Y494500D03*
X244100Y499900D03*
X246800Y496800D03*
X257400Y481637D03*
X256300Y486000D03*
Y490000D03*
X260646Y499181D03*
X256855Y499154D03*
X265019Y497483D03*
X255487Y512454D03*
X242800Y495486D03*
X246500Y493400D03*
X240450Y499400D03*
X236737Y493170D03*
X260407Y502674D03*
X257207D03*
X246300Y482000D03*
X239139Y525077D03*
X239321Y521081D03*
X249700Y525737D03*
Y521250D03*
X264500Y521309D03*
X261100Y521250D03*
X250100Y537100D03*
X263300Y526300D03*
X234777Y550569D03*
X252238Y574238D03*
X253500Y590500D03*
X257413D03*
X266100Y614400D03*
X265850Y606400D03*
X248500Y583000D03*
X260100Y647400D03*
X259300Y632400D03*
Y639300D03*
X250500Y642500D03*
X265900Y622400D03*
X238100Y643400D03*
X247717Y633233D03*
X259300Y635900D03*
X236000Y656000D03*
X256600Y652200D03*
X241000Y712500D03*
X262628Y744470D03*
X266980Y723854D03*
X241000Y721500D03*
X258100Y726100D03*
X241000Y725500D03*
Y718000D03*
X263181Y772181D03*
X266561Y830301D03*
X253962D03*
X263361D03*
X250762D03*
X260261Y875176D03*
X238213D03*
X257061D03*
X235013D03*
X290000Y141100D03*
X274250Y133750D03*
X292000Y130000D03*
X285500D03*
X284440Y139580D03*
X285250Y133750D03*
X294500Y152500D03*
X286100Y153900D03*
X280000D03*
X290500Y152500D03*
X275000Y147500D03*
X277800Y208500D03*
X271231Y237031D03*
X283622Y226340D03*
X279257D03*
X269849Y308414D03*
X282700Y300100D03*
X299600Y297662D03*
X269270Y315759D03*
X287200Y326802D03*
X287800Y311600D03*
X267979Y342500D03*
X295400Y325390D03*
X283700Y322100D03*
X297729Y362571D03*
X288270Y365240D03*
X294009Y363063D03*
X293800Y436100D03*
X301170Y462780D03*
X301162Y459290D03*
X273783Y476100D03*
X283400Y477900D03*
X284200Y465000D03*
X290838Y501600D03*
X286181Y498546D03*
X291500Y497700D03*
X269000Y504962D03*
X275286Y504392D03*
X280749Y512744D03*
X282400Y487300D03*
X295876Y520800D03*
X296200Y566900D03*
X290000Y578165D03*
X300835D03*
X279994Y554794D03*
X283600Y551400D03*
X291000Y561450D03*
X280200Y551400D03*
X289835Y583165D03*
Y588165D03*
X269000Y589000D03*
X269335Y593165D03*
X300835Y583165D03*
X301000Y588665D03*
X288835Y593165D03*
X276300Y617350D03*
X281700Y634900D03*
X271500Y639500D03*
X281100Y651700D03*
X285500Y704900D03*
X298406Y706000D03*
X290338Y715800D03*
X278406Y716531D03*
X274406Y716598D03*
X270000Y732650D03*
X283161Y730092D03*
X275609Y726886D03*
X270556Y716702D03*
X269500Y736150D03*
X286500Y740500D03*
X287278Y729031D03*
X286406Y716531D03*
X296132Y726171D03*
X290720Y726333D03*
X285333Y726241D03*
X282406Y716598D03*
X298620Y728596D03*
X283500Y765631D03*
X268193Y755633D03*
X293692Y765571D03*
X287115Y765584D03*
X281500Y752000D03*
X299184Y765691D03*
X279159Y830301D03*
X275959D03*
X285500Y866200D03*
X272859Y875176D03*
X282300Y866200D03*
X269659Y875176D03*
X307300Y221702D03*
X307834Y237966D03*
X306900Y251000D03*
X302500Y251600D03*
X311882Y310550D03*
X306800Y290500D03*
X328842Y300042D03*
X307425Y309838D03*
X303517Y309777D03*
X312900Y290450D03*
X321300Y301500D03*
X334200Y299600D03*
X313200Y299900D03*
X331800Y309100D03*
X310485Y314670D03*
X328800Y315900D03*
X316420Y331830D03*
X302749Y332651D03*
X326041Y329282D03*
Y325000D03*
X315900Y320900D03*
X313100Y371038D03*
Y374438D03*
X301320Y362500D03*
X313875Y364201D03*
X310475Y364193D03*
X316315Y369889D03*
X316205Y376006D03*
X313500Y437400D03*
Y441000D03*
X313300Y429603D03*
X313294Y434006D03*
X302140Y444160D03*
X306521Y463576D03*
X304293Y466146D03*
X329014Y472022D03*
X306612Y460177D03*
X307400Y467600D03*
X303440Y475360D03*
X322268Y466591D03*
X322305Y469991D03*
X321900Y459800D03*
X322036Y463198D03*
X327512Y509612D03*
X303800Y505100D03*
X304400Y511400D03*
X327589Y504300D03*
X333102Y485902D03*
X330000Y501900D03*
X303500Y491000D03*
X320500Y531000D03*
X321000Y527000D03*
X322700Y536500D03*
X311406Y535944D03*
X306900Y529100D03*
X311500Y548000D03*
X314900D03*
X322100Y638500D03*
X309000Y679000D03*
X305500Y676400D03*
X334800Y712000D03*
X302406Y706031D03*
X306406D03*
X322178Y729178D03*
X310016Y729793D03*
X312500Y716500D03*
X317300Y739300D03*
X302000Y740800D03*
X320000Y718200D03*
X323600Y717800D03*
X301310Y726403D03*
X326000Y729000D03*
X315132Y727197D03*
X307278Y726198D03*
X311200Y765500D03*
X311406Y775198D03*
X302700Y765400D03*
X315406Y765598D03*
Y775200D03*
X307406Y775198D03*
X329553Y830301D03*
X316954D03*
X326353D03*
X313754D03*
X323253Y875176D03*
X310955Y865676D03*
X332651Y875176D03*
X320053D03*
X307755Y865676D03*
X362528Y123931D03*
X358917Y124122D03*
X355069D03*
X352600Y128200D03*
Y132537D03*
X337000Y162000D03*
X345820Y256570D03*
X349970Y256720D03*
X344958Y300740D03*
X344955Y305843D03*
X341652Y305034D03*
Y301534D03*
X362500Y341700D03*
X362825Y336000D03*
X359132Y326647D03*
X351515Y327915D03*
X356953Y353653D03*
X359403Y351203D03*
X352003Y358603D03*
X354505Y356102D03*
X360820Y359299D03*
X363270Y356940D03*
X355872Y363965D03*
X358362Y361649D03*
X359500Y448800D03*
X335570Y491460D03*
X342300Y511600D03*
X350000Y537600D03*
X347100Y605300D03*
X357600Y638300D03*
X367000Y704000D03*
X360000D03*
X344200Y696300D03*
X354300Y696000D03*
Y704500D03*
X363500Y704000D03*
X342900Y727200D03*
X364354Y731801D03*
X362091Y729538D03*
X367675Y723000D03*
X367348Y830301D03*
X354750D03*
X342151D03*
X364148D03*
X351550D03*
X338951D03*
X361048Y875176D03*
X348450D03*
X335851D03*
X357848D03*
X345250D03*
X401300Y159800D03*
X401200Y150200D03*
X401300Y156715D03*
Y153215D03*
X400400Y189100D03*
X383600Y203200D03*
X376600Y261350D03*
X381700Y265800D03*
X368900Y315700D03*
X370700Y353900D03*
X395100Y449100D03*
X380300Y508700D03*
X401000Y575500D03*
X372000Y579300D03*
X388900Y550400D03*
X386500Y607900D03*
X370500Y705500D03*
X370875Y723000D03*
X401994Y830301D03*
X389396D03*
X398794D03*
X386196D03*
X395694Y875176D03*
X383096D03*
X392494D03*
X379896D03*
X406500Y141700D03*
X403600Y142542D03*
X433000Y169700D03*
X406500Y146900D03*
X435161Y166892D03*
X403600Y146042D03*
X422876Y199830D03*
Y204195D03*
X421757Y177999D03*
X411400Y183900D03*
X410900Y217100D03*
X404170Y326708D03*
X403900Y315492D03*
X404040Y318900D03*
Y323300D03*
X416100Y470800D03*
X418900Y529300D03*
X410300Y637500D03*
X427191Y830301D03*
X414593D03*
X423991D03*
X411393D03*
X420891Y875176D03*
X408292D03*
X417691D03*
X405092D03*
X461900Y62300D03*
X465127Y57727D03*
X452600Y114254D03*
X454871Y122291D03*
X457400Y138900D03*
X452500Y153300D03*
X438561Y166892D03*
X456500Y169783D03*
Y165418D03*
X464086Y287614D03*
X461389Y318510D03*
X464086Y340500D03*
X459200Y369300D03*
X462700D03*
X455450Y376050D03*
X466700Y388800D03*
X469700Y393300D03*
X459450Y384050D03*
X448200Y531400D03*
X443000Y596500D03*
X469000Y784000D03*
X461300Y813100D03*
X457900D03*
X470200Y62300D03*
X478400D03*
X496782Y134315D03*
X480910Y164099D03*
X480800Y160700D03*
X498900Y171800D03*
X498000Y194200D03*
X477037Y333841D03*
X473637Y333876D03*
X500198Y324041D03*
X480532Y321332D03*
X480000Y355800D03*
X476600D03*
X486700Y363800D03*
X470200D03*
X493700Y369300D03*
X490200Y388800D03*
X491860Y382140D03*
X487000Y393300D03*
X480368Y405606D03*
X476531D03*
X472600Y477700D03*
X487400Y492100D03*
X500800Y567200D03*
X482925Y777422D03*
X489522Y780127D03*
X478000Y777500D03*
X483850Y773800D03*
X500778Y781031D03*
X499906Y768531D03*
X497910Y778824D03*
X495906Y768598D03*
X480100Y784575D03*
X497000Y817500D03*
X483000Y788150D03*
X499000Y793000D03*
X485300Y811750D03*
X500415Y817532D03*
X494582Y804000D03*
X477206Y820648D03*
X500700Y828100D03*
X500807Y831499D03*
X491906Y827403D03*
X487906D03*
X509369Y141559D03*
X530800Y123900D03*
X507861Y134154D03*
X519300Y138871D03*
X530177Y140708D03*
X516100Y138871D03*
X526977Y140708D03*
X529176Y151713D03*
X532560Y152046D03*
X534000Y167400D03*
X535960Y151999D03*
X507300Y175500D03*
X503975Y172372D03*
X518686Y163800D03*
Y168200D03*
X517599Y229658D03*
X531232Y229927D03*
X510462Y261315D03*
X525881Y287776D03*
X509143Y284391D03*
X529881Y287376D03*
X525347Y336979D03*
X512100Y319700D03*
X532499Y315591D03*
X533779Y336979D03*
X507809Y336341D03*
X522209Y333841D03*
X522409Y318441D03*
X529126Y342336D03*
X532978Y371023D03*
X534500Y395100D03*
X528850Y394750D03*
X518100Y453200D03*
X520500Y519400D03*
X515900Y768300D03*
X531500Y774500D03*
X531600Y770200D03*
X515278Y779198D03*
X519748Y768297D03*
X507729Y778198D03*
X504278Y779198D03*
X507906Y768531D03*
X528179Y782555D03*
X524795Y778529D03*
X511484Y778515D03*
X515650Y764500D03*
X503906Y768598D03*
X519906Y764900D03*
X532000Y792500D03*
X515000D03*
X524700Y817500D03*
X507044Y817569D03*
X516943Y817401D03*
X528906Y817598D03*
X512716Y817550D03*
X508579Y827421D03*
X527500Y836200D03*
X512679Y827500D03*
X562603Y140881D03*
X544800Y137769D03*
X541600D03*
X549100Y126900D03*
X566531Y143123D03*
X570754Y147365D03*
X546800Y163450D03*
X564483Y167935D03*
X558121Y167249D03*
X548700Y152200D03*
X545500D03*
X547173Y167987D03*
X561567Y205767D03*
X569500Y240225D03*
X546494Y216010D03*
X539798Y228856D03*
X539934Y232660D03*
X540035Y236294D03*
X541637Y263240D03*
X545974D03*
X541681Y297976D03*
X539481Y286676D03*
X544993Y281352D03*
X539450Y322166D03*
X539507Y330787D03*
X554400Y335900D03*
X539400Y376444D03*
X556500Y358000D03*
X561300Y369500D03*
X552720Y364180D03*
X539400Y380781D03*
X550000Y381000D03*
X559973Y387638D03*
X561912Y390762D03*
X567150Y415750D03*
X560900Y413700D03*
X544000Y761000D03*
X540500Y781000D03*
X547395Y761198D03*
X540500Y761000D03*
X561050Y830301D03*
X548451D03*
X570448D03*
X557850D03*
X545251D03*
X567348Y875176D03*
X554750D03*
X542151D03*
X564148D03*
X551550D03*
X538951D03*
X577650Y137780D03*
X587850Y137800D03*
X604450Y137780D03*
X574450D03*
X584650Y137800D03*
X601250Y137780D03*
X597350Y149950D03*
X594150D03*
X596253Y210000D03*
X603000Y190710D03*
X579811Y179500D03*
X582400Y209500D03*
X597813Y220858D03*
X587438Y230850D03*
X576100Y234500D03*
X592563Y228308D03*
X588963Y227408D03*
X587400Y238200D03*
X600800Y337400D03*
X597600Y339100D03*
X604400Y421200D03*
X579900Y427400D03*
X600400Y538000D03*
X598845Y830301D03*
X586246D03*
X573648D03*
X595645D03*
X583046D03*
X592545Y875176D03*
X579947D03*
X601944D03*
X589345D03*
X576747D03*
X614721Y138287D03*
X608089Y131519D03*
X627826Y137880D03*
X638150D03*
X624626D03*
X634950D03*
X617000Y144500D03*
X636950Y149650D03*
X635482Y207733D03*
X607700Y211800D03*
X608800Y221400D03*
X635863Y216308D03*
X635190Y219641D03*
X631063Y242108D03*
X616970Y235017D03*
X629663Y221708D03*
X616718Y238408D03*
X627363Y224358D03*
X637300Y234500D03*
X628563Y249108D03*
X624101Y330010D03*
X627500Y329900D03*
X622629Y344635D03*
X616640Y342230D03*
X620000Y341500D03*
X618600Y357100D03*
X609000Y390350D03*
X615500Y420100D03*
X619100Y418000D03*
X636640Y830301D03*
X624042D03*
X611443D03*
X633440D03*
X620842D03*
X608243D03*
X630340Y875176D03*
X617742D03*
X605144D03*
X627140D03*
X614542D03*
X654500Y143000D03*
X647000D03*
X640150Y149650D03*
X640400Y218200D03*
X649400Y234500D03*
X642463Y241608D03*
X638963D03*
X660700Y212000D03*
X643000Y343000D03*
X643750Y321500D03*
X640550D03*
X643000Y369500D03*
X648792Y358431D03*
X660244Y352200D03*
Y349000D03*
X645800Y780500D03*
Y776900D03*
Y783900D03*
X671285Y830301D03*
X658687D03*
X668085D03*
X655487D03*
X664986Y875176D03*
X652388D03*
X661786D03*
X649188D03*
X687900Y208100D03*
X697494Y186256D03*
Y181919D03*
X693300Y181200D03*
X674500Y212000D03*
X680100Y378718D03*
X683600D03*
X696482Y830301D03*
X683884D03*
X693282D03*
X680684D03*
X702400Y868800D03*
X690183Y875176D03*
X677585D03*
X699200Y868800D03*
X686983Y875176D03*
X674385D03*
X728395Y-7315D03*
X713461Y-3006D03*
X736308Y-7483D03*
X711919Y6754D03*
X729132Y3575D03*
X729555Y33100D03*
X709120Y35980D03*
X719555Y33100D03*
X735186Y20714D03*
X729000Y24800D03*
X725314Y24751D03*
X721890Y24887D03*
X719008Y21999D03*
X722955Y33095D03*
X726155D03*
X727265Y52588D03*
X726646Y42651D03*
X721690Y53340D03*
X726609Y49251D03*
Y46051D03*
X732900Y44900D03*
X730021Y42235D03*
X732500Y98421D03*
X720800Y102150D03*
Y93150D03*
Y78150D03*
X732500Y101621D03*
X720800Y105350D03*
Y96350D03*
Y81350D03*
Y114150D03*
Y117350D03*
X713000Y310000D03*
X712495Y816195D03*
X727978Y830301D03*
X737377D03*
X724778D03*
X714900Y818600D03*
X734277Y875176D03*
X731077D03*
X746329Y-7789D03*
X771715Y6840D03*
X752763Y38638D03*
X771600Y24200D03*
X741600Y41000D03*
X747000Y44300D03*
X762250Y44650D03*
X755700Y79100D03*
X749800Y91400D03*
X753700Y102900D03*
X759600Y79200D03*
X743490Y111940D03*
X765000Y112800D03*
X768777Y171450D03*
X761242Y169242D03*
X765579D03*
X771400Y185919D03*
X766244Y185897D03*
X748237Y194042D03*
X751737D03*
X766950Y189252D03*
X763562Y189539D03*
X770385Y189165D03*
X749337Y212192D03*
X746037Y213992D03*
X746237Y210392D03*
X765774Y830301D03*
X753175D03*
X740577D03*
X762574D03*
X749975D03*
X772073Y875176D03*
X759474D03*
X746876D03*
X768873D03*
X756274D03*
X743676D03*
X790150Y-1400D03*
X788408Y-4321D03*
X798061Y-6439D03*
X788550Y29350D03*
X806152Y51692D03*
X791300Y74200D03*
X775381Y66115D03*
X778800Y66388D03*
X782551Y67144D03*
X786333Y66963D03*
X791200Y125300D03*
X796051Y175147D03*
X806665Y174050D03*
X803265D03*
X792760Y176043D03*
X799000Y196000D03*
X802200D03*
X796089Y181182D03*
X775397Y179165D03*
Y184215D03*
X792390Y199166D03*
X786463Y199019D03*
X803169Y198850D03*
X797890Y198918D03*
X792000Y195778D03*
X787600Y195804D03*
X773984Y189118D03*
X792760Y180443D03*
X778807Y183890D03*
Y179490D03*
X780800Y545900D03*
X803569Y830301D03*
X790970D03*
X778372D03*
X800369D03*
X787770D03*
X775172D03*
X797270Y875176D03*
X784671D03*
X806668D03*
X794070D03*
X781471D03*
X807514Y2199D03*
X813900Y12900D03*
X830773Y9000D03*
X834227D03*
X831592Y34411D03*
X838252Y20800D03*
X834500D03*
X830500D03*
X828283Y24734D03*
X824462Y25770D03*
X823996Y44276D03*
X832401Y46472D03*
X820004Y44234D03*
X828700Y48800D03*
X808114Y67634D03*
X816043Y94981D03*
Y99318D03*
X823551Y80551D03*
X819000Y97100D03*
X809000Y76000D03*
X810000Y109400D03*
X840500Y735500D03*
X837000D03*
X839990Y789230D03*
X816167Y830301D03*
X838164D03*
X812967D03*
X835065Y875176D03*
X809868D03*
X831865D03*
X861000Y350D03*
X857453Y303D03*
X867600Y2500D03*
X863300Y23575D03*
X851100Y9100D03*
X855489Y9811D03*
X859300Y9900D03*
X874300Y18875D03*
X858500Y40000D03*
Y32000D03*
X869447Y31024D03*
X843500Y9150D03*
X849051Y20908D03*
X845052Y20800D03*
X841652D03*
X870600Y18915D03*
X854252Y20800D03*
X851870Y52160D03*
X859200Y47100D03*
X847337Y46563D03*
X851300Y45748D03*
X848623Y70757D03*
X852019Y70589D03*
X855421Y70551D03*
X858821Y70614D03*
X868800Y49200D03*
Y85300D03*
X871696Y87082D03*
X868200Y116000D03*
X846702Y117371D03*
X854400Y117500D03*
X861300Y117800D03*
X864800Y707700D03*
X868200D03*
X852895Y748648D03*
X869406Y745531D03*
X848000Y735500D03*
X865406Y745598D03*
X873367Y745335D03*
X844000Y735500D03*
X854049Y757573D03*
X857406Y755198D03*
X861406D03*
X858126Y763600D03*
X841500Y771000D03*
X874000Y772000D03*
X869562Y758457D03*
X844500Y758000D03*
X867410Y755824D03*
X866878Y794531D03*
X853500Y798000D03*
X846706Y797648D03*
X870278Y794531D03*
X874570Y811820D03*
X861406Y804403D03*
X857406D03*
X853962Y830301D03*
X841364D03*
X850762D03*
X847663Y875176D03*
X844463D03*
X883800Y-500D03*
X881700Y2300D03*
X904262Y14894D03*
X887800Y40100D03*
X880883Y30583D03*
X892745Y9681D03*
X900200Y9600D03*
X883800Y41400D03*
X907750Y51750D03*
X894110Y49250D03*
X878800Y49600D03*
X875050Y56250D03*
X895080Y52828D03*
X905488Y54479D03*
X878394Y85780D03*
X875001Y86003D03*
X901899Y85942D03*
X892900Y85300D03*
X885042Y85292D03*
X888600Y85700D03*
X897600Y85500D03*
X908500Y270500D03*
Y275000D03*
Y267000D03*
X895800Y738400D03*
X893400Y745100D03*
X884700Y721100D03*
X896500Y734000D03*
X877000Y745000D03*
X892100Y721100D03*
X881200Y721300D03*
X888400Y721400D03*
X889900Y769600D03*
X884778Y756198D03*
X876036Y755481D03*
X894465Y755501D03*
X891056Y755641D03*
X882227Y758835D03*
X894200Y794500D03*
X877930Y796880D03*
X876470Y808710D03*
X906396Y810300D03*
X886288Y794372D03*
X898700Y794200D03*
Y816000D03*
X882290Y796770D03*
X881720Y807390D03*
X906450Y806900D03*
X906092Y813687D03*
X894406Y818000D03*
X888100Y823338D03*
X890200Y819200D03*
X912000Y41000D03*
X927250Y31450D03*
X915486Y41030D03*
X918952Y40680D03*
X912000Y45000D03*
X939064Y58104D03*
X934881Y57322D03*
X909797Y55037D03*
X910000Y85300D03*
X937642Y85562D03*
X926093Y85239D03*
X929213Y86593D03*
X934438Y86700D03*
X919050Y85500D03*
X913979Y86580D03*
X929800Y105900D03*
X909000Y279000D03*
X909500Y283000D03*
X969100Y14600D03*
X942500Y30100D03*
X970064Y18764D03*
X963700Y21700D03*
X959877Y26978D03*
X967180Y66705D03*
X949102Y74964D03*
X959300Y68600D03*
Y72000D03*
X964105Y62308D03*
X959855Y61107D03*
X956687Y85482D03*
X942800Y85700D03*
X948200Y85900D03*
X953301Y85793D03*
X956500Y108000D03*
X949500Y103000D03*
X949893Y106378D03*
X949828Y109778D03*
X960500Y607000D03*
X953500D03*
X956900D03*
X976500Y4500D03*
X1008353Y-1940D03*
X985579Y26494D03*
X985403Y22993D03*
X980100Y14500D03*
X1000985Y29307D03*
X1007921Y39585D03*
X985315Y14425D03*
X997385Y29307D03*
X994650Y39880D03*
X992396Y45073D03*
X990628Y49698D03*
X997007Y49560D03*
X1008508Y47704D03*
X982500Y271500D03*
Y275500D03*
X982000Y267500D03*
X983500Y279500D03*
Y283500D03*
X1006100Y528700D03*
X977500Y550000D03*
X1025700Y7600D03*
X1022711Y-4975D03*
X1012177Y-2940D03*
X1019859Y-7642D03*
X1033017Y14743D03*
X1024330Y34379D03*
X1040218Y32140D03*
X1010229Y19022D03*
X1022300Y13900D03*
X1033554Y30216D03*
X1030139Y30209D03*
X1024432Y43718D03*
X1035783Y51473D03*
X1017863Y45056D03*
X1040241Y61043D03*
X1033517Y48934D03*
X1036854Y47110D03*
X1019900Y108500D03*
X1015948D03*
X1034500D03*
X1027483Y108431D03*
X1024000Y108500D03*
X1037900D03*
X1041300D03*
X1030883Y108438D03*
X1022600Y542100D03*
X1041314Y830301D03*
X1038214Y875176D03*
X1035014D03*
X1062044Y-4173D03*
X1065620Y-4335D03*
X1072800Y-800D03*
X1069200Y-4200D03*
X1060800Y10100D03*
X1061253Y17487D03*
X1062470Y31823D03*
X1062433Y37099D03*
X1056049Y18396D03*
X1061153Y27488D03*
X1046200Y24500D03*
X1054835Y40386D03*
X1072140Y16447D03*
X1047429Y15229D03*
X1044050Y28815D03*
X1065700Y32888D03*
Y36088D03*
X1061200Y20888D03*
Y24088D03*
X1056200Y10100D03*
X1065657Y28946D03*
X1047500Y41500D03*
X1051000D03*
X1076970Y30411D03*
X1052600Y14400D03*
X1054210Y53370D03*
X1054090Y58470D03*
X1068315Y56120D03*
X1068390Y61611D03*
X1074103Y44988D03*
X1049772Y57259D03*
X1049470Y53749D03*
X1057000Y54500D03*
X1071135Y60375D03*
X1057000Y57700D03*
X1071135Y57175D03*
X1057000Y107700D03*
X1048100Y108500D03*
X1044700D03*
X1061000Y111000D03*
X1053000Y109500D03*
X1069711Y830301D03*
X1057112D03*
X1044514D03*
X1066511D03*
X1053912D03*
X1076010Y875176D03*
X1050813D03*
X1072810D03*
X1047613D03*
X1084000Y500D03*
X1083315Y36654D03*
X1082808Y30601D03*
X1092094Y30362D03*
X1080672Y9500D03*
X1084800Y9400D03*
X1083379Y40889D03*
X1083500Y25500D03*
X1082974Y14467D03*
X1105441Y54768D03*
X1100992Y52374D03*
X1078694Y43478D03*
X1103300Y73900D03*
X1103349Y70700D03*
X1088005Y46541D03*
X1088287Y55917D03*
X1096496Y51226D03*
X1107506Y830301D03*
X1094907D03*
X1082309D03*
X1104306D03*
X1091707D03*
X1079109D03*
X1101207Y875176D03*
X1088608D03*
X1110605D03*
X1098007D03*
X1085408D03*
X1112700Y80700D03*
X1114842Y83078D03*
X1122001Y126574D03*
Y136874D03*
X1135150Y137851D03*
X1122001Y133324D03*
X1141900Y137851D03*
X1122001Y130124D03*
X1138700Y137851D03*
X1126500Y222500D03*
X1135750Y228750D03*
X1143000Y242000D03*
X1132703Y830301D03*
X1120104D03*
X1142101D03*
X1129503D03*
X1116904D03*
X1139002Y875176D03*
X1126403D03*
X1113805D03*
X1135802D03*
X1123203D03*
X1154557Y138505D03*
X1145450Y137851D03*
X1161307Y138505D03*
X1158107D03*
X1170400Y144100D03*
X1150250Y228750D03*
X1147000Y242000D03*
X1151000D03*
X1157899Y830301D03*
X1145301D03*
X1176747D03*
X1154699D03*
X1164199Y875176D03*
X1151600D03*
X1160999D03*
X1148400D03*
X1182061Y142478D03*
X1190835Y137899D03*
X1199400Y142851D03*
X1178861Y142478D03*
X1187635Y137899D03*
X1196200Y142851D03*
X1206991Y156730D03*
X1203791D03*
X1201000Y417900D03*
X1196600Y416200D03*
X1192545Y830301D03*
X1179947D03*
X1189345D03*
X1199000Y867200D03*
X1186246Y875176D03*
X1195800Y867300D03*
X1183046Y875176D03*
X1214795Y142443D03*
X1234209Y142463D03*
X1242900Y137851D03*
X1225348Y137960D03*
X1231009Y142463D03*
X1239700Y137851D03*
X1222148Y137960D03*
X1242621Y153690D03*
X1236640Y830301D03*
X1224042D03*
X1233440D03*
X1220842D03*
X1242939Y875176D03*
X1230340D03*
X1239739D03*
X1227140D03*
X1277265Y137673D03*
X1274065D03*
X1273499Y151498D03*
X1273520Y148070D03*
X1261944Y145770D03*
X1258744D03*
X1251801Y144871D03*
X1255000Y317300D03*
X1270500Y335500D03*
X1272500Y350000D03*
X1275060Y345690D03*
X1277620Y349500D03*
X1264820Y349320D03*
X1249250Y390250D03*
X1269500Y397000D03*
X1273500Y400500D03*
X1258000Y421500D03*
X1274435Y830301D03*
X1261837D03*
X1249239D03*
X1271235D03*
X1258637D03*
X1246039D03*
X1268136Y875176D03*
X1255537D03*
X1277534D03*
X1264936D03*
X1252337D03*
X1303983Y22083D03*
X1304000Y44000D03*
Y67500D03*
Y90500D03*
X1286543Y141581D03*
X1296017Y137478D03*
X1283343Y141581D03*
X1292817Y137478D03*
X1290000Y271000D03*
X1308500Y262500D03*
X1311200Y256500D03*
X1293500Y271000D03*
X1312200Y275200D03*
X1303700Y289500D03*
X1288900Y304000D03*
X1283300Y302900D03*
X1309900Y292400D03*
X1310500Y285500D03*
X1281900Y346580D03*
X1282740Y350010D03*
X1293280Y345770D03*
X1289960Y349900D03*
X1299000Y347500D03*
X1311500Y391000D03*
X1310068Y394084D03*
X1297625Y382375D03*
X1296500Y386500D03*
X1290125Y382875D03*
X1289500Y386500D03*
X1282740Y383000D03*
X1282000Y386500D03*
X1296400Y542400D03*
X1301000Y618500D03*
X1300000Y637000D03*
X1297617Y677117D03*
X1286800Y671100D03*
X1297500Y664000D03*
X1310207D03*
X1297400Y651300D03*
X1290550D03*
X1302000Y695500D03*
X1302128Y685500D03*
X1307000Y686500D03*
X1304500Y698000D03*
X1301728Y714600D03*
X1312132Y684293D03*
X1310500Y723000D03*
X1291428Y726117D03*
X1306128Y732872D03*
X1302128D03*
X1312231Y830301D03*
X1287033D03*
X1309031D03*
X1283833D03*
X1305931Y875176D03*
X1293333D03*
X1280734D03*
X1302731D03*
X1290133D03*
X1339471Y139268D03*
X1316590Y147210D03*
X1317400Y143620D03*
X1340130Y145980D03*
X1331243Y182198D03*
X1322000Y276500D03*
X1322500Y266800D03*
X1333500Y290500D03*
X1317026Y304858D03*
X1314000Y286500D03*
X1313607Y664000D03*
X1327200Y661800D03*
X1331000Y662000D03*
X1326128Y674000D03*
X1340000D03*
X1317007Y664000D03*
X1334128Y674000D03*
X1337500Y698000D03*
X1322439Y697767D03*
X1315000Y686500D03*
X1329500Y684667D03*
X1321928Y683798D03*
X1318500Y684667D03*
X1339934Y683832D03*
X1336795Y685141D03*
X1326758Y686678D03*
X1314628Y733000D03*
X1315000Y723000D03*
X1333500D03*
X1334128Y732667D03*
X1325600Y722987D03*
X1342000Y732500D03*
X1337500Y723000D03*
X1340500Y742500D03*
X1338128Y732872D03*
X1330128Y732667D03*
X1337427Y830301D03*
X1324829D03*
X1346825D03*
X1334227D03*
X1321629D03*
X1343726Y875176D03*
X1331128D03*
X1318529D03*
X1340526D03*
X1327928D03*
X1315329D03*
X1359128Y167226D03*
X1355321Y172119D03*
X1354971Y167446D03*
X1365804Y185197D03*
X1368300Y267800D03*
X1358662Y275485D03*
X1355066Y275228D03*
X1348500Y276500D03*
X1361500Y273500D03*
X1352000Y276700D03*
X1352500Y267000D03*
X1355000Y286300D03*
X1364000Y280500D03*
X1369700Y424600D03*
X1366000Y472900D03*
X1351500Y675000D03*
X1350025Y830301D03*
X1381696Y173459D03*
X1387196Y174160D03*
X1382138Y184129D03*
X1385467Y180543D03*
G54D24*
X113300Y276600D03*
X113000Y280500D03*
X113100Y284100D03*
X294000Y716000D03*
X300500Y715613D03*
G54D21*
X92990Y252362D03*
X116790D03*
X1301120Y173278D03*
Y183908D03*
G54D34*
X514309Y-315D03*
X557616D03*
X600923D03*
X644230D03*
X687537D03*
G54D32*
X473231Y235560D03*
Y274930D03*
X487404Y255245D03*
G54D36*
X533010Y69803D03*
X535962Y64292D03*
X524151Y69803D03*
X527104Y64292D03*
X535962Y49331D03*
X527104D03*
X533010Y54843D03*
X524151D03*
X533010Y99725D03*
X535962Y94213D03*
X524151Y99725D03*
X527104Y94213D03*
X533010Y84764D03*
X535962Y79252D03*
X524151Y84764D03*
X527104Y79252D03*
X567458Y54843D03*
X570411Y49331D03*
Y64292D03*
X567458Y69803D03*
X541868D03*
X544821Y64292D03*
Y49331D03*
X541868Y54843D03*
X570411Y79252D03*
Y94213D03*
X567458Y84764D03*
Y99725D03*
X541868D03*
X544821Y94213D03*
X541868Y84764D03*
X544821Y79252D03*
X576317Y54843D03*
X585175D03*
X579269Y49331D03*
X588128D03*
X576317Y69803D03*
X585175D03*
X579269Y64292D03*
X588128D03*
X579269Y79252D03*
X588128D03*
X585175Y84764D03*
X576317D03*
Y99725D03*
X585175D03*
X579269Y94213D03*
X588128D03*
X619624Y54843D03*
X628482D03*
X622577Y49331D03*
X631435D03*
X619624Y69803D03*
X628482D03*
X622577Y64292D03*
X631435D03*
X610766Y54843D03*
X613718Y49331D03*
Y64292D03*
X610766Y69803D03*
X622577Y79252D03*
X631435D03*
X628482Y84764D03*
X619624D03*
Y99725D03*
X628482D03*
X622577Y94213D03*
X631435D03*
X613718Y79252D03*
Y94213D03*
X610766Y84764D03*
Y99725D03*
X662931Y54843D03*
X671789D03*
X665884Y49331D03*
X662931Y69803D03*
X671789D03*
X665884Y64292D03*
X654073Y54843D03*
X657025Y49331D03*
Y64292D03*
X654073Y69803D03*
X665884Y79252D03*
X671789Y84764D03*
X662931D03*
Y99725D03*
X671789D03*
X665884Y94213D03*
X657025Y79252D03*
Y94213D03*
X654073Y84764D03*
Y99725D03*
X674742Y49331D03*
Y64292D03*
Y79252D03*
Y94213D03*
X1135372Y69803D03*
X1144230D03*
X1138324Y64292D03*
X1126513Y69803D03*
X1129466Y64292D03*
X1138324Y49331D03*
X1129466D03*
X1144230Y54843D03*
X1135372D03*
X1126513D03*
X1135372Y99725D03*
X1144230D03*
X1138324Y94213D03*
X1126513Y99725D03*
X1129466Y94213D03*
X1135372Y84764D03*
X1144230D03*
X1138324Y79252D03*
X1126513Y84764D03*
X1129466Y79252D03*
X1178679Y54843D03*
Y69803D03*
X1169820Y54843D03*
X1172773Y49331D03*
Y64292D03*
X1169820Y69803D03*
X1147183Y64292D03*
Y49331D03*
X1178679Y84764D03*
Y99725D03*
X1172773Y79252D03*
Y94213D03*
X1169820Y84764D03*
Y99725D03*
X1147183Y94213D03*
Y79252D03*
X1187537Y54843D03*
X1181631Y49331D03*
X1190490D03*
X1187537Y69803D03*
X1181631Y64292D03*
X1190490D03*
X1181631Y79252D03*
X1190490D03*
X1187537Y84764D03*
Y99725D03*
X1181631Y94213D03*
X1190490D03*
X1221986Y54843D03*
X1230844D03*
X1224939Y49331D03*
X1233797D03*
X1221986Y69803D03*
X1230844D03*
X1224939Y64292D03*
X1233797D03*
X1213128Y54843D03*
X1216080Y49331D03*
Y64292D03*
X1213128Y69803D03*
X1224939Y79252D03*
X1233797D03*
X1230844Y84764D03*
X1221986D03*
Y99725D03*
X1230844D03*
X1224939Y94213D03*
X1233797D03*
X1216080Y79252D03*
Y94213D03*
X1213128Y84764D03*
Y99725D03*
X1265293Y54843D03*
X1274151D03*
X1268246Y49331D03*
X1277104D03*
X1265293Y69803D03*
X1274151D03*
X1268246Y64292D03*
X1277104D03*
X1256435Y54843D03*
X1259387Y49331D03*
Y64292D03*
X1256435Y69803D03*
X1268246Y79252D03*
X1277104D03*
X1274151Y84764D03*
X1265293D03*
Y99725D03*
X1274151D03*
X1268246Y94213D03*
X1277104D03*
X1259387Y79252D03*
Y94213D03*
X1256435Y84764D03*
Y99725D03*
G54D13*
X26977Y151614D03*
X96189D03*
G54D28*
X158170Y314302D03*
X162670D03*
X153670D03*
X156170Y318302D03*
X160670D03*
X224500Y170500D03*
Y174700D03*
Y166300D03*
Y178900D03*
X259500Y138500D03*
X261500Y173500D03*
X253000Y166500D03*
X258700D03*
X262900D03*
X243000Y176500D03*
X243500Y166500D03*
Y162000D03*
Y157000D03*
X261500Y179000D03*
Y184500D03*
X261000Y190500D03*
X258225Y193963D03*
X266500Y184500D03*
Y190500D03*
X243000Y181000D03*
Y186000D03*
X239900Y600100D03*
X240000Y608600D03*
Y604400D03*
X271000Y184500D03*
X536081Y304376D03*
X536809Y298789D03*
X557904Y327115D03*
X585515Y276459D03*
X583009Y264117D03*
X585351Y269292D03*
X587984Y246148D03*
X587980Y251975D03*
X589164Y264150D03*
X582738Y273300D03*
X587063Y257608D03*
X582976Y246148D03*
X583286Y251974D03*
X582682Y257614D03*
X589400Y308626D03*
X585737Y289608D03*
Y283108D03*
X582683Y279618D03*
X582411Y286589D03*
X582363Y293408D03*
X580563Y308608D03*
X583391Y298870D03*
X583282Y303091D03*
X703600Y233700D03*
X695963Y302308D03*
Y297808D03*
Y293308D03*
X690663Y287608D03*
Y292108D03*
X725300Y228700D03*
X730300D03*
X711300D03*
X716300D03*
X716900Y233800D03*
X721400D03*
X730400D03*
X725900D03*
X735400D03*
X707900D03*
X712400D03*
X706800Y290700D03*
X718800Y291000D03*
X714300D03*
X723300D03*
X732300D03*
X727800D03*
X737300D03*
X921300Y74700D03*
X918100Y71900D03*
X929464Y49420D03*
X925022Y42909D03*
X929713Y44849D03*
X930500Y57500D03*
X976066Y26581D03*
X971466Y26681D03*
X975086Y61900D03*
X970000Y61050D03*
X985880Y41686D03*
X980566Y26581D03*
X985880Y46086D03*
Y50586D03*
X1171300Y215700D03*
X1166300D03*
X1175999D03*
X1168000Y280000D03*
X1173000D03*
X1177500D03*
X1190300Y215700D03*
X1185300D03*
X1208800D03*
X1203800D03*
X1180601D03*
X1199300D03*
X1194500D03*
X1187000Y280000D03*
X1192000D03*
X1205500D03*
X1210500D03*
X1182500D03*
X1201000D03*
X1196200D03*
X1214800Y215700D03*
X1366672Y210312D03*
X1360844Y210366D03*
X1355944Y210313D03*
X1351525Y207104D03*
X1351545Y202879D03*
Y198575D03*
X1375196Y217203D03*
X1367042Y223895D03*
X1375359Y230110D03*
X1372000Y240500D03*
X1351777Y227823D03*
X1360644Y223881D03*
X1350987Y236754D03*
X1351668Y232125D03*
X1355644Y223881D03*
X1351899Y219598D03*
X1351954Y215268D03*
X1354989Y239016D03*
X1350950Y241000D03*
X1349639Y211374D03*
X1349298Y223737D03*
X1372000Y245300D03*
Y249500D03*
X1355050Y247300D03*
X1350950Y246100D03*
G54D37*
X943111Y5908D03*
X935236D03*
X927361D03*
X919486D03*
X911616D03*
X943111Y13778D03*
X935236D03*
X927361D03*
X919486D03*
X911616D03*
X958856Y5908D03*
X950986D03*
X958856Y13778D03*
X950986D03*
G54D18*
X41603Y177598D03*
X65579D03*
X57587D03*
X49595D03*
X45559Y187598D03*
X37567D03*
X53551D03*
X73571Y177598D03*
X81563D03*
X77607Y187598D03*
X69615D03*
X85599D03*
G54D25*
X122700Y476100D03*
Y478400D03*
X122600Y473800D03*
Y471500D03*
X121673Y491672D03*
X130985Y504300D03*
X124822Y504271D03*
X127973Y504272D03*
X121673Y497973D03*
Y494822D03*
X118524Y491672D03*
X118500Y504238D03*
X115373Y504271D03*
X127973Y510571D03*
X124823D03*
X121673D03*
X131121Y513721D03*
X121673D03*
X131121Y510570D03*
X127971Y513721D03*
X124821D03*
X127971Y494823D03*
X131122Y491674D03*
X127973Y488524D03*
X131122D03*
Y485374D03*
X121673Y504272D03*
X124823Y501122D03*
X121673D03*
X127973Y497973D03*
X124822Y488523D03*
X127973Y491674D03*
X124823Y497973D03*
Y491674D03*
X127973Y485374D03*
X124823Y494822D03*
X131121Y494823D03*
X127973Y501122D03*
Y529469D03*
X124823Y523170D03*
Y542067D03*
X127973Y532618D03*
Y542067D03*
X124823Y532617D03*
X124822Y545216D03*
X131122Y532618D03*
X124823Y535766D03*
X127973Y538918D03*
X121673Y545215D03*
Y523170D03*
X131121Y529467D03*
Y520018D03*
X127971D03*
X131121Y523168D03*
X124822Y520019D03*
X121673Y520020D03*
X115374Y529467D03*
X118524D03*
X121673D03*
X124823D03*
X121673Y532617D03*
X124822Y538917D03*
X121673Y535766D03*
X127973Y523170D03*
X121673Y538916D03*
X126869Y577770D03*
X122547Y564452D03*
Y558100D03*
Y551748D03*
X121601Y574686D03*
X126801Y574386D03*
X124900Y559638D03*
X124847Y550110D03*
X124900Y556462D03*
Y565990D03*
Y562814D03*
Y553286D03*
X122547Y561276D03*
Y554924D03*
Y567628D03*
X131369Y610945D03*
X115622Y604646D03*
X121911Y614076D03*
X131369Y588898D03*
X121922Y592048D03*
X118771Y595196D03*
X125072Y610945D03*
X125070Y598347D03*
X131370Y601496D03*
X118773Y601495D03*
X126646Y606400D03*
X115622Y614094D03*
Y601496D03*
X121922Y610945D03*
X128220Y614095D03*
X118773Y604645D03*
X125070Y614095D03*
X118773Y598345D03*
X118805Y614099D03*
X115623Y598345D03*
X118773Y610945D03*
X131369Y614095D03*
X118773Y589748D03*
X128221Y610945D03*
X121922Y588872D03*
X118773Y592048D03*
X121922Y617244D03*
X128221D03*
X131369D03*
X118771D03*
X125070D03*
X125072Y620392D03*
X121921D03*
X140571Y491674D03*
X140570Y488523D03*
X162618Y485374D03*
X150020Y491674D03*
X156319Y485374D03*
X146870Y491674D03*
Y482225D03*
X150020Y510571D03*
X153169D03*
X146870D03*
X153169Y513721D03*
X146870D03*
X150020D03*
X143721Y491674D03*
Y488524D03*
Y485374D03*
X140569Y494823D03*
X134270Y510571D03*
X165768Y488524D03*
X153170Y491674D03*
X150020Y485374D03*
Y482225D03*
X146870Y485374D03*
Y488524D03*
X162618D03*
Y491674D03*
X134272D03*
X165768D03*
X134272Y488524D03*
Y485374D03*
X137421Y491674D03*
Y485374D03*
X140571D03*
X156318Y488523D03*
X156319Y491674D03*
X153169Y485374D03*
Y488524D03*
X159469Y491674D03*
Y488524D03*
Y485374D03*
X150020Y488524D03*
X137421D03*
X165766Y542066D03*
X143721Y532618D03*
X146870Y516870D03*
X150020D03*
X153169D03*
X137421Y535768D03*
Y542066D03*
X134270Y538916D03*
X137421Y532618D03*
X134272Y542066D03*
Y535768D03*
X140570Y535767D03*
X137421Y538918D03*
X153188Y538899D03*
X162617Y535766D03*
X146869Y538954D03*
X146858Y535742D03*
X159449Y542048D03*
Y538898D03*
X159456Y532642D03*
X162617Y542066D03*
Y538916D03*
X149981Y538917D03*
X153132Y535767D03*
X149985Y535771D03*
X153194Y542078D03*
X153187Y532636D03*
X140571Y532618D03*
X143718Y538953D03*
X143686Y542070D03*
X146869Y529469D03*
X134270Y523170D03*
X153168Y529469D03*
X140569D03*
X134272Y532618D03*
X162618D03*
X165766Y538916D03*
X151989Y552538D03*
X147451Y554136D03*
X142951Y553336D03*
X161280Y553800D03*
Y561700D03*
Y564000D03*
X147451Y551836D03*
Y549536D03*
X142951Y551036D03*
X161280Y566300D03*
X159537Y548256D03*
X147451Y556436D03*
X142951Y555636D03*
X160700Y551356D03*
X151989Y557138D03*
X161280Y556100D03*
X151989Y554838D03*
X161280Y558400D03*
X143968Y614095D03*
X143967Y610945D03*
X137669Y604645D03*
X162865Y595196D03*
Y604645D03*
X156566Y610945D03*
X159716Y598345D03*
X153417Y614095D03*
X150269D03*
X153418Y595197D03*
X162865Y610945D03*
X137661Y614096D03*
X137670Y595197D03*
X147143Y595184D03*
X137669Y610945D03*
Y601495D03*
X140818D03*
X134521Y595196D03*
X134519Y614095D03*
X150269Y598347D03*
X156566Y614095D03*
X143968Y601495D03*
X140821Y614106D03*
X166016Y601496D03*
X159716Y610945D03*
Y614095D03*
Y595197D03*
X166016Y610944D03*
X162867Y614095D03*
X147115Y598360D03*
X150268Y601496D03*
X147141Y614096D03*
X143968Y588898D03*
X153417Y610945D03*
X159716Y604645D03*
X166015Y598345D03*
X147117Y610945D03*
X162865Y601495D03*
X150268Y610944D03*
X159716Y601495D03*
X140818Y610945D03*
X134520Y610944D03*
X153418Y592048D03*
X159716D03*
X134521Y598345D03*
X143968Y592048D03*
X147117Y601495D03*
X143969Y617244D03*
X162881Y617266D03*
X153417Y617244D03*
X150251Y617226D03*
X134521Y617266D03*
X137671D03*
X140821D03*
X156566Y617244D03*
X159716D03*
X150351Y620436D03*
X181514Y479075D03*
X172065Y513721D03*
X175215D03*
X178365Y510571D03*
X175215D03*
X172065D03*
Y501122D03*
X178365Y507422D03*
X175215D03*
Y491674D03*
Y497973D03*
X172065Y491674D03*
X175215Y485374D03*
X175217Y482225D03*
X175215Y501122D03*
X178365D03*
X184664Y485372D03*
X172065Y494823D03*
X178365Y491674D03*
X181514Y488524D03*
X184664Y488522D03*
X175215Y494823D03*
X172065Y497973D03*
X178365Y494823D03*
X172065Y485374D03*
X172067Y482225D03*
X178365Y497973D03*
X172065Y504272D03*
X175216Y504271D03*
X172065Y507422D03*
X178365Y504272D03*
X168916Y510571D03*
X178365Y513721D03*
X172065Y488524D03*
X175216Y488523D03*
X178365Y485374D03*
Y488524D03*
X181514Y485374D03*
X178365Y520020D03*
X181514D03*
X172065Y535768D03*
Y526319D03*
X178365Y529469D03*
X175215D03*
X172065D03*
X175215Y523170D03*
X178365D03*
X175216Y535767D03*
X184664Y516869D03*
X172065Y523170D03*
Y520020D03*
X175216Y520019D03*
X168916Y523170D03*
X175215Y526319D03*
Y532618D03*
X178365Y535768D03*
X172065Y532618D03*
X175215Y538918D03*
X168916Y535766D03*
X172065Y538918D03*
X168916Y542066D03*
Y538916D03*
X178365Y532618D03*
X874410Y127953D03*
Y139764D03*
Y131890D03*
Y120079D03*
Y124016D03*
Y163386D03*
Y155512D03*
Y147638D03*
Y202755D03*
Y206692D03*
Y194881D03*
Y183071D03*
Y242125D03*
Y238188D03*
Y230314D03*
Y222440D03*
Y214566D03*
Y257873D03*
Y253936D03*
Y249999D03*
Y246062D03*
X905906Y127953D03*
X894095Y139764D03*
X890158Y127953D03*
X901969D03*
X898032D03*
X894095D03*
X882284Y139764D03*
X886221Y135827D03*
X882284Y131890D03*
X886221Y127953D03*
X882284D03*
X878347D03*
X901969Y139764D03*
Y135827D03*
Y131890D03*
X886221Y139764D03*
X890158Y135827D03*
X886221Y131890D03*
X890158Y139764D03*
X894095Y135827D03*
X890158Y131890D03*
X878347Y135827D03*
Y116142D03*
X882284Y120079D03*
X886221Y116142D03*
X890158Y120079D03*
X894095Y116142D03*
X898032Y120079D03*
X901969Y116142D03*
X878347Y139764D03*
X882284Y135827D03*
X878347Y131890D03*
Y120079D03*
X882300Y124032D03*
X886221Y120079D03*
X890158Y124016D03*
X894095Y120079D03*
X898032Y124016D03*
X901969Y120079D03*
X905906Y139764D03*
Y135827D03*
Y131890D03*
X886221Y171260D03*
X901969Y167323D03*
X905906D03*
X901969Y171260D03*
X905906D03*
X901969Y175197D03*
X905906D03*
X890158Y163386D03*
X894095Y167323D03*
Y175197D03*
X905906Y159449D03*
X901969D03*
X894095Y155512D03*
Y147638D03*
X882284Y167323D03*
X886221Y163386D03*
X882284D03*
X878347D03*
X886221Y159449D03*
X882284Y155512D03*
X886221Y151575D03*
X882284Y147638D03*
X886221Y143701D03*
X901969Y147638D03*
Y143701D03*
X890158Y159449D03*
X886221Y155512D03*
X890158Y151575D03*
X886221Y147638D03*
X890158Y143701D03*
X894095Y159449D03*
X890158Y155512D03*
X894095Y151575D03*
X890158Y147638D03*
X894095Y143701D03*
X878347Y159449D03*
Y151575D03*
Y143701D03*
X882284Y159449D03*
X878347Y155512D03*
X882284Y151575D03*
X878347Y147638D03*
X882284Y143701D03*
X905906Y155512D03*
Y151575D03*
Y147638D03*
Y143701D03*
X901969Y155512D03*
Y151575D03*
Y194881D03*
X905906D03*
X901969Y198818D03*
X905906D03*
X901969Y202755D03*
X905906D03*
X901969Y206692D03*
X905906D03*
X890158Y202755D03*
X898032Y206692D03*
X894095D03*
Y194881D03*
X901969Y179134D03*
X905906D03*
X901969Y190944D03*
X905906D03*
X894095Y183071D03*
X882284Y206692D03*
X886221Y202755D03*
X882284D03*
X878347D03*
X886221Y198818D03*
X882284Y194881D03*
X886221Y190944D03*
Y179134D03*
Y206692D03*
X890158Y198818D03*
X886221Y194881D03*
X890158Y190944D03*
X886221Y183071D03*
X890158Y179134D03*
Y206692D03*
X894095Y198818D03*
X890158Y194881D03*
X894095Y190944D03*
X890158Y183071D03*
X894095Y179134D03*
X878347Y198818D03*
Y190944D03*
Y206692D03*
X882284Y198818D03*
X878347Y194881D03*
X882284Y190944D03*
X878347Y183071D03*
X901969Y222440D03*
X905906D03*
X901969Y226377D03*
X905906D03*
Y234251D03*
X901969Y230314D03*
X905906D03*
X901969Y234251D03*
X894095Y222440D03*
X890158Y238188D03*
X894095Y242125D03*
Y230314D03*
X901969Y242125D03*
Y210629D03*
X905906D03*
X901969Y214566D03*
X905906D03*
X901969Y218503D03*
X905906D03*
X894095Y214566D03*
X886221Y226377D03*
X882284Y222440D03*
X886221Y242125D03*
X878347D03*
X886221Y238188D03*
X882284D03*
X878347D03*
X886221Y234251D03*
X882284Y230314D03*
X886221Y218503D03*
X882284Y214566D03*
X886221Y210629D03*
X890158Y234251D03*
X886221Y230314D03*
X890158Y226377D03*
X886221Y222440D03*
X890158Y218503D03*
X886221Y214566D03*
X890158Y210629D03*
X905906Y242125D03*
X898032D03*
X890158D03*
X882284D03*
X894095Y234251D03*
X890158Y230314D03*
X894095Y226377D03*
X890158Y222440D03*
X894095Y218503D03*
X890158Y214566D03*
X894095Y210629D03*
X878347Y234251D03*
Y226377D03*
Y218503D03*
Y210629D03*
X882284Y234251D03*
X878347Y230314D03*
X882284Y226377D03*
X878347Y222440D03*
X882284Y218503D03*
X878347Y214566D03*
X882284Y210629D03*
X901969Y253936D03*
X894095D03*
X890158Y249999D03*
X905906D03*
X898032D03*
X878347Y253936D03*
X886221D03*
X882284Y249999D03*
X905906Y246062D03*
X901969Y249999D03*
X898032Y246062D03*
X894095Y249999D03*
X890158Y246062D03*
X886221Y249999D03*
X882284Y246062D03*
X878347Y249999D03*
X901969Y246062D03*
X894095D03*
X886221D03*
X878347D03*
X905906Y257873D03*
X901969Y261810D03*
X898032Y257873D03*
X894095Y261810D03*
X890158Y257873D03*
X886221Y261810D03*
X882284Y257873D03*
X878347Y261810D03*
X905906Y253936D03*
X901969Y257873D03*
X898032Y253936D03*
X894095Y257873D03*
X890158Y253936D03*
X886221Y257873D03*
X882284Y253936D03*
X878347Y257873D03*
X909843Y131890D03*
X941339Y127953D03*
X913780Y131890D03*
Y127953D03*
Y139764D03*
X921654Y127953D03*
X929528D03*
X937402Y139764D03*
Y127953D03*
X941339Y139764D03*
X933465D03*
X921654Y135827D03*
X941339Y124016D03*
Y120079D03*
Y116142D03*
X937402Y124016D03*
X933465Y127953D03*
X929528Y124016D03*
X925591Y127953D03*
X921654Y124016D03*
X917717Y127953D03*
X909843Y135827D03*
X913780Y124016D03*
X909843Y127953D03*
X921654Y139764D03*
X929528D03*
X925591D03*
X921654Y131890D03*
X941339D03*
Y135827D03*
X933465Y131890D03*
Y135827D03*
X937402Y131890D03*
Y135827D03*
X929528Y131890D03*
Y135827D03*
X925591Y131890D03*
Y135827D03*
X909843Y120079D03*
X913780Y116142D03*
X917717Y120079D03*
X921654Y116142D03*
X925591Y120079D03*
X929528Y116142D03*
X933465Y120079D03*
X937402Y116142D03*
X909843Y124016D03*
X913780Y120079D03*
X917717Y124016D03*
X921654Y120079D03*
X925591Y124016D03*
X929528Y120079D03*
X933465Y124016D03*
X937402Y120079D03*
X913780Y135827D03*
X917717Y139764D03*
Y131890D03*
Y135827D03*
X909843Y139764D03*
X937402Y155512D03*
X941339Y151575D03*
Y155512D03*
X929528Y159449D03*
X913780Y143701D03*
Y159449D03*
X937402D03*
X925591Y151575D03*
X913780Y147638D03*
X917717Y159449D03*
X913780Y155512D03*
Y151575D03*
X941339Y175197D03*
Y167323D03*
X933465Y175197D03*
X937402Y171260D03*
X933465Y167323D03*
X937402Y163386D03*
X929528Y171260D03*
X925591Y175197D03*
X921654Y163386D03*
X925591Y167323D03*
X917717D03*
X921654Y171260D03*
X917717Y175197D03*
X929528Y163386D03*
X941339Y159449D03*
X937402Y151575D03*
X933465Y159449D03*
X925591D03*
X921654Y147638D03*
X909843Y163386D03*
X913780D03*
X909843Y167323D03*
X913780D03*
X909843Y171260D03*
X913780D03*
X909843Y175197D03*
X913780D03*
X909843Y147638D03*
X933465Y151575D03*
Y155512D03*
X921654Y151575D03*
X929528D03*
Y155512D03*
X925591Y143701D03*
Y147638D03*
Y155512D03*
X909843Y159449D03*
Y143701D03*
Y155512D03*
X941339Y143701D03*
Y147638D03*
X933465Y143701D03*
Y147638D03*
X937402Y143701D03*
Y147638D03*
X929528Y143701D03*
Y147638D03*
X917717Y155512D03*
Y151575D03*
Y143701D03*
Y147638D03*
X921654Y155512D03*
X917717Y179134D03*
X913780Y183071D03*
X925591Y194881D03*
X921654Y198818D03*
X917717Y202755D03*
X937402Y206692D03*
X941339Y202755D03*
Y194881D03*
X937402Y198818D03*
X933465Y202755D03*
X929528Y206692D03*
X933465Y194881D03*
X929528Y198818D03*
X925591Y202755D03*
X921654Y206692D03*
X917717Y194881D03*
X937402Y179134D03*
X933465Y183071D03*
X929528Y190944D03*
Y179134D03*
X925591Y183071D03*
X921654Y179134D03*
X937402Y190944D03*
X917717Y183071D03*
X921654Y190944D03*
X909843Y194881D03*
X913780D03*
X909843Y198818D03*
X913780D03*
X909843Y202755D03*
X913780D03*
X909843Y206692D03*
X913780D03*
X909843Y179134D03*
X913780D03*
X909843Y183071D03*
Y190944D03*
X913780D03*
Y214566D03*
X941339Y226377D03*
X937402Y222440D03*
X933465Y226377D03*
X929528Y222440D03*
X925591Y226377D03*
X929528Y230314D03*
X937402D03*
X941339Y234251D03*
X937402Y238188D03*
X933465Y234251D03*
X929528Y238188D03*
X925591Y234251D03*
X917717Y222440D03*
Y226377D03*
X921654Y222440D03*
Y226377D03*
X917717Y230314D03*
Y234251D03*
X921654Y230314D03*
Y234251D03*
X925591Y230314D03*
Y222440D03*
X933465D03*
X941339D03*
X937402Y226377D03*
X929528D03*
X941339Y238188D03*
Y230314D03*
X937402Y242125D03*
Y234251D03*
X933465Y238188D03*
Y230314D03*
X929528Y242125D03*
Y234251D03*
X925591Y238188D03*
X921654Y242125D03*
X929528Y214566D03*
X933465Y210629D03*
X925591D03*
X917717D03*
X921654Y218503D03*
X925591D03*
X929528D03*
X933465D03*
X937402D03*
X941339D03*
X921654Y214566D03*
X917717Y218503D03*
X937402Y214566D03*
X913780Y226377D03*
X909843Y222440D03*
X913780D03*
X909843Y226377D03*
Y230314D03*
Y234251D03*
X913780Y230314D03*
Y234251D03*
Y242125D03*
X909843D03*
Y214566D03*
Y210629D03*
X913780D03*
X909843Y218503D03*
X913780D03*
X941339Y242125D03*
X933465D03*
X925591D03*
X917717D03*
X937402Y253936D03*
X929528D03*
X921654D03*
X941339Y249999D03*
X933465D03*
X925591D03*
X917717D03*
X913780Y253936D03*
X909843Y261810D03*
Y257873D03*
Y253936D03*
Y249999D03*
Y246062D03*
X941339D03*
X937402Y249999D03*
X933465Y246062D03*
X929528Y249999D03*
X925591Y246062D03*
X921654Y249999D03*
X917717Y246062D03*
X913780Y249999D03*
X937402Y246062D03*
X929528D03*
X921654D03*
X913780D03*
X941339Y257873D03*
X937402Y261810D03*
X933465Y257873D03*
X929528Y261810D03*
X925591Y257873D03*
X921654Y261810D03*
X917717Y257873D03*
X913780Y261810D03*
X941339Y253936D03*
X937402Y257873D03*
X933465Y253936D03*
X929528Y257873D03*
X925591Y253936D03*
X921654Y257873D03*
X917717Y253936D03*
X913780Y257873D03*
X953149Y127953D03*
X949212D03*
Y139764D03*
X957086Y127953D03*
X964960D03*
X972834D03*
X957086Y139764D03*
X953149Y135827D03*
X968897Y139764D03*
X953149Y124016D03*
Y120079D03*
Y116142D03*
X972834Y124016D03*
X968897Y127953D03*
X964960Y124016D03*
X961023Y127953D03*
X957086Y124016D03*
X972834Y139764D03*
X953149D03*
Y131890D03*
X957086D03*
X964960D03*
X961023Y139764D03*
Y131890D03*
Y135827D03*
X957086D03*
Y116142D03*
X961023Y120079D03*
X964960Y116142D03*
X968897Y120079D03*
X972834Y116142D03*
X957086Y120079D03*
X961023Y124016D03*
X964960Y120079D03*
X968897Y124016D03*
X972834Y120079D03*
Y135827D03*
Y131890D03*
X964960Y135827D03*
Y139764D03*
X968897Y135827D03*
Y131890D03*
X949212Y155512D03*
X953149Y163386D03*
X968897Y151575D03*
X964960Y159449D03*
X957086D03*
X953149Y151575D03*
X949212Y159449D03*
X972834D03*
X953149Y167323D03*
X957086Y163386D03*
X949212Y171260D03*
Y163386D03*
X972834Y171260D03*
X968897Y175197D03*
X972834Y163386D03*
X968897Y167323D03*
X964960Y171260D03*
X961023Y175197D03*
Y167323D03*
X964960Y163386D03*
X953149Y175197D03*
X957086Y171260D03*
X953149Y159449D03*
X949212Y151575D03*
X972834Y147638D03*
X968897Y159449D03*
X961023D03*
Y147638D03*
X972834Y151575D03*
X957086Y143701D03*
X961023D03*
X957086Y151575D03*
Y147638D03*
Y155512D03*
X953149Y143701D03*
Y155512D03*
X949212Y143701D03*
Y147638D03*
X964960Y143701D03*
X961023Y155512D03*
Y151575D03*
X964960Y155512D03*
Y151575D03*
X968897Y155512D03*
X964960Y147638D03*
X968897D03*
Y143701D03*
X972834D03*
Y155512D03*
X964960Y198818D03*
X961023Y202755D03*
X957086Y206692D03*
X968897Y194881D03*
X953149D03*
X949212Y198818D03*
Y206692D03*
X953149Y202755D03*
X961023Y194881D03*
X957086Y198818D03*
X972834Y206692D03*
Y198818D03*
X968897Y202755D03*
X964960Y206692D03*
X972834Y190944D03*
X964960Y179134D03*
X961023Y183071D03*
X957086Y190944D03*
X953149Y183071D03*
X957086Y179134D03*
X949212D03*
X964960Y190944D03*
X968897Y183071D03*
X972834Y179134D03*
X968897Y226377D03*
Y234251D03*
X953149Y226377D03*
X949212Y222440D03*
Y230314D03*
X964960Y222440D03*
X961023Y226377D03*
X957086Y222440D03*
X964960Y230314D03*
X957086D03*
X953149Y234251D03*
X949212Y238188D03*
X964960D03*
X961023Y234251D03*
X957086Y238188D03*
X972834Y222440D03*
Y226377D03*
Y230314D03*
Y234251D03*
X968897Y230314D03*
Y222440D03*
X953149D03*
X961023D03*
X972834Y242125D03*
X949212Y226377D03*
X964960D03*
X957086D03*
X953149Y238188D03*
Y230314D03*
X949212Y242125D03*
Y234251D03*
X968897Y238188D03*
X964960Y242125D03*
Y234251D03*
X961023Y238188D03*
Y230314D03*
X957086Y242125D03*
Y234251D03*
X949212Y214566D03*
X953149Y210629D03*
X968897D03*
X964960Y214566D03*
X972834Y218503D03*
X949212D03*
X953149D03*
X957086Y214566D03*
X961023Y210629D03*
X972834Y214566D03*
X957086Y218503D03*
X961023D03*
X964960D03*
X968897D03*
Y242125D03*
X961023D03*
X953149D03*
X972834Y253936D03*
X949212Y261810D03*
Y257873D03*
Y253936D03*
X964960D03*
X957086D03*
X953149Y249999D03*
X949212D03*
Y246062D03*
X968897Y249999D03*
X961023D03*
X972834D03*
X968897Y246062D03*
X964960Y249999D03*
X961023Y246062D03*
X957086Y249999D03*
X953149Y246062D03*
X972834D03*
X964960D03*
X957086D03*
X972834Y261810D03*
X968897Y257873D03*
X964960Y261810D03*
X961023Y257873D03*
X957086Y261810D03*
X953149Y257873D03*
X972834D03*
X968897Y253936D03*
X964960Y257873D03*
X961023Y253936D03*
X957086Y257873D03*
X953149Y253936D03*
X992519Y139764D03*
X996456D03*
Y131890D03*
Y135827D03*
X1000393Y131890D03*
X980708Y127953D03*
Y139764D03*
X1008267Y135827D03*
Y127953D03*
Y124016D03*
X984645Y135827D03*
X1000393Y139764D03*
X992519Y127953D03*
Y124016D03*
X988582Y127953D03*
Y124016D03*
Y120079D03*
Y116142D03*
X984645Y127953D03*
X980708Y124016D03*
X996456Y127953D03*
X1000393Y124016D03*
Y127953D03*
X1004330D03*
X976771D03*
X980708Y135827D03*
Y131890D03*
X1008267Y139764D03*
X976771Y120079D03*
X980708Y116142D03*
X984645Y120079D03*
X1008267Y131890D03*
X1004330Y135827D03*
Y139764D03*
X976771Y124016D03*
X980708Y120079D03*
X984645Y124016D03*
X1004330Y131890D03*
X1000393Y135827D03*
X992519Y115742D03*
X996456Y120079D03*
X1000393Y116142D03*
X1004330Y120079D03*
X1008267Y116142D03*
X992519Y120079D03*
X996456Y124016D03*
X1000393Y120079D03*
X1004330Y124016D03*
X1008267Y120079D03*
X988582Y139764D03*
Y135827D03*
X984645Y131890D03*
X976771D03*
Y139764D03*
X988582Y131890D03*
X984645Y139764D03*
X976771Y135827D03*
X996456Y163386D03*
X1000393D03*
X996456Y167323D03*
Y171260D03*
Y175197D03*
X992519Y163386D03*
X988582D03*
X980708Y175197D03*
X996456Y143701D03*
Y147638D03*
Y151575D03*
Y155512D03*
Y159449D03*
X1008267Y163386D03*
Y171260D03*
Y159449D03*
Y143701D03*
Y151575D03*
X980708Y163386D03*
X984645D03*
X988582Y167323D03*
X992519D03*
X980708D03*
X984645D03*
X988582Y171260D03*
X992519D03*
X980708D03*
X984645D03*
X988582Y175197D03*
X992519D03*
X984645D03*
X1000393Y167323D03*
X1004330Y163386D03*
X1000393Y175197D03*
X988582Y159449D03*
X992519D03*
X984645Y147638D03*
X1000393D03*
Y155512D03*
X976771Y167323D03*
Y175197D03*
X980708Y159449D03*
Y155512D03*
X976771Y151575D03*
X1004330Y143701D03*
X1008267Y147638D03*
X1004330Y151575D03*
X1008267Y155512D03*
X1004330Y159449D03*
X1008267Y167323D03*
X1004330Y171260D03*
X1008267Y175197D03*
X1000393Y143701D03*
X1004330Y147638D03*
X1000393Y151575D03*
X1004330Y155512D03*
X1000393Y159449D03*
X1004330Y167323D03*
X1000393Y171260D03*
X1004330Y175197D03*
X988582Y147638D03*
Y143701D03*
X984645Y155512D03*
Y151575D03*
Y143701D03*
X988582Y151575D03*
X976771Y147638D03*
X980708Y143701D03*
X976771Y155512D03*
X980708Y147638D03*
Y151575D03*
X976771Y159449D03*
Y143701D03*
X996456Y194881D03*
Y198818D03*
Y202755D03*
X1000393D03*
X996456Y179134D03*
Y183071D03*
Y190944D03*
X992519Y183071D03*
X988582D03*
X976771Y179134D03*
X980708Y183071D03*
X1008267Y202755D03*
Y198818D03*
Y190944D03*
Y179134D03*
X980708Y198818D03*
X988582Y194881D03*
X992519D03*
X980708D03*
X984645D03*
X988582Y198818D03*
X992519D03*
X984645D03*
X988582Y202755D03*
X992519D03*
X980708D03*
X984645D03*
X988582Y206692D03*
X992519D03*
X980708D03*
X984645D03*
X1000393D03*
X996456D03*
X1004330Y202755D03*
X1000393Y194881D03*
X988582Y179134D03*
X992519D03*
X988582Y190944D03*
X992519D03*
X980708D03*
X984645D03*
X980708Y179134D03*
X984645D03*
Y183071D03*
X1000393D03*
X976771Y202755D03*
Y194881D03*
Y183071D03*
X1004330Y179134D03*
X1008267Y183071D03*
X1004330Y190944D03*
X1008267Y194881D03*
X1004330Y198818D03*
X1008267Y206692D03*
X1000393Y179134D03*
X1004330Y183071D03*
X1000393Y190944D03*
X1004330Y194881D03*
X1000393Y198818D03*
X1004330Y206692D03*
X996456Y214566D03*
Y210629D03*
X976771Y214566D03*
X980708D03*
X1008267Y226377D03*
Y242125D03*
Y238188D03*
Y234251D03*
Y218503D03*
Y210629D03*
X1000393Y222440D03*
X988582D03*
X992519D03*
X980708D03*
X984645D03*
X988582Y226377D03*
X992519D03*
X984645D03*
X980708D03*
X988582Y230314D03*
X992519D03*
Y234251D03*
X980708Y230314D03*
Y234251D03*
X984645Y230314D03*
Y234251D03*
X988582D03*
X1000393Y230314D03*
X1004330Y238188D03*
X1000393Y242125D03*
X980708D03*
X984645D03*
X992519D03*
X984645Y214566D03*
X988582Y210629D03*
X992519D03*
X980708D03*
X984645D03*
X988582Y214566D03*
X992519D03*
X988582Y218503D03*
X992519D03*
X980708D03*
X984645D03*
X1000393Y214566D03*
X976771Y222440D03*
Y226377D03*
Y230314D03*
Y234251D03*
Y210629D03*
Y218503D03*
X1004330Y210629D03*
X1008267Y214566D03*
X1004330Y218503D03*
X1008267Y222440D03*
X1004330Y226377D03*
X1008267Y230314D03*
X1004330Y234251D03*
X1000393Y210629D03*
X1004330Y214566D03*
X1000393Y218503D03*
X1004330Y222440D03*
X1000393Y226377D03*
X1004330Y230314D03*
X1000393Y234251D03*
X1004330Y242125D03*
X996456D03*
X988582D03*
X976771D03*
X1008267Y253936D03*
X980708D03*
X984645D03*
Y257873D03*
Y261810D03*
X992519Y253936D03*
X1000393D03*
X984645Y246062D03*
Y249999D03*
X988582D03*
X996456D03*
X1004330D03*
X976771D03*
X1008267D03*
X1004330Y246062D03*
X1000393Y249999D03*
X996456Y246062D03*
X992519Y249999D03*
X988582Y246062D03*
X980708Y249999D03*
X976771Y246062D03*
X1008267D03*
X1000393D03*
X992519D03*
X980708D03*
X1008267Y261810D03*
X1004330Y257873D03*
X1000393Y261810D03*
X996456Y257873D03*
X992519Y261810D03*
X988582Y257873D03*
X980708Y261810D03*
X976771Y257873D03*
X1008267D03*
X1004330Y253936D03*
X1000393Y257873D03*
X996456Y253936D03*
X992519Y257873D03*
X988582Y253936D03*
X980708Y257873D03*
X976771Y253936D03*
X1021751Y117469D03*
X1012204Y131890D03*
Y139764D03*
Y127953D03*
X1016141Y124016D03*
X1020078Y127953D03*
X1016141D03*
X1020078Y139764D03*
X1012204Y120079D03*
X1016141Y116142D03*
X1020078Y120079D03*
Y131890D03*
X1016141Y135827D03*
Y139764D03*
X1012204Y124016D03*
X1016141Y120079D03*
X1023278D03*
X1016141Y131890D03*
X1012204Y135827D03*
Y167323D03*
Y163386D03*
X1016141D03*
X1020078D03*
X1012204Y175197D03*
Y147638D03*
Y155512D03*
X1016141Y143701D03*
X1020078Y147638D03*
X1016141Y151575D03*
X1020078Y155512D03*
X1016141Y159449D03*
X1020078Y167323D03*
X1016141Y171260D03*
X1020078Y175197D03*
X1012204Y143701D03*
X1016141Y147638D03*
X1012204Y151575D03*
X1016141Y155512D03*
X1012204Y159449D03*
X1016141Y167323D03*
X1012204Y171260D03*
X1016141Y175197D03*
X1012204Y206692D03*
Y202755D03*
Y194881D03*
X1016141Y202755D03*
X1020078D03*
X1012204Y183071D03*
X1016141Y179134D03*
X1020078Y183071D03*
X1016141Y190944D03*
X1020078Y194881D03*
X1016141Y198818D03*
X1020078Y206692D03*
X1012204Y179134D03*
X1016141Y183071D03*
X1012204Y190944D03*
X1016141Y194881D03*
X1012204Y198818D03*
X1016141Y206692D03*
X1012204Y222440D03*
Y238188D03*
Y230314D03*
X1016141Y242125D03*
X1020078D03*
X1016141Y238188D03*
X1020078D03*
X1012204Y214566D03*
Y242125D03*
X1016141Y210629D03*
X1020078Y214566D03*
X1016141Y218503D03*
X1020078Y222440D03*
X1016141Y226377D03*
X1020078Y230314D03*
X1016141Y234251D03*
X1012204Y210629D03*
X1016141Y214566D03*
X1012204Y218503D03*
X1016141Y222440D03*
X1012204Y226377D03*
X1016141Y230314D03*
X1012204Y234251D03*
X1020078Y257873D03*
X1016141Y253936D03*
X1020078D03*
X1012204Y249999D03*
X1020078D03*
Y246062D03*
X1016141Y249999D03*
X1012204Y246062D03*
X1016141D03*
Y261810D03*
X1012204Y257873D03*
X1016141D03*
X1012204Y253936D03*
G54D23*
X134251Y153543D03*
X151968D03*
X144094D03*
X1027722Y-9125D03*
X1054494D03*
G54D31*
X476614Y167493D03*
Y162493D03*
Y157493D03*
G54D29*
X193900Y274372D03*
X183900D03*
X213900D03*
X203900D03*
X302500Y207200D03*
X292500D03*
X326200D03*
X336200D03*
X312500D03*
X346200D03*
X465485Y200680D03*
Y190680D03*
Y180680D03*
X488462Y180761D03*
Y190761D03*
Y200761D03*
X526215Y184000D03*
X511742Y215594D03*
X521742D03*
X531742D03*
X565585Y184000D03*
X772300Y16200D03*
X762300D03*
X752300D03*
X785300Y16100D03*
X795300D03*
X805300D03*
X819291Y265354D03*
Y285354D03*
X1075197Y92126D03*
Y112126D03*
X1348785Y161642D03*
X1323195D03*
G54D12*
X31977Y126614D03*
Y116614D03*
X91189Y126614D03*
Y116614D03*
Y136614D03*
G54D26*
X106900Y738600D03*
Y721300D03*
X115000Y717600D03*
X275900Y467300D03*
X623498Y140671D03*
G54D11*
X18577Y107902D03*
X5500Y119571D03*
Y139571D03*
Y159571D03*
X22000Y167200D03*
X5500Y179571D03*
Y199571D03*
X26500Y199500D03*
X21900Y199700D03*
X21800Y188100D03*
X5500Y219571D03*
Y239571D03*
X27300Y229000D03*
X5500Y259571D03*
Y279571D03*
Y299571D03*
X24000Y308700D03*
X5500Y339571D03*
Y319571D03*
X24639Y321239D03*
X5500Y359571D03*
Y399571D03*
Y379571D03*
Y419571D03*
Y439571D03*
X21300Y429500D03*
X5500Y479571D03*
Y459571D03*
Y499571D03*
Y519571D03*
Y539571D03*
Y579571D03*
Y559571D03*
Y599571D03*
Y639571D03*
Y619571D03*
Y679571D03*
Y659571D03*
Y699571D03*
X27125Y695275D03*
X18250Y749250D03*
X5500Y719571D03*
Y739571D03*
Y779571D03*
Y759571D03*
Y799571D03*
X10020Y835051D03*
X30020D03*
X5500Y819571D03*
X31400Y209190D03*
X46760Y209157D03*
X63250Y205050D03*
X42800Y200100D03*
X47912Y294940D03*
X58100Y334600D03*
X62400Y334500D03*
X39300Y389557D03*
X36750Y462900D03*
X53200Y462500D03*
X63519Y505320D03*
X62298Y484200D03*
X35700Y488500D03*
X55950Y572500D03*
X50020Y835051D03*
X96584Y195100D03*
X78050Y196300D03*
X82676Y208785D03*
X67600Y209500D03*
X95200Y210800D03*
X77527Y255800D03*
X94530Y264671D03*
X89400Y279300D03*
X76055Y357145D03*
X79267Y410185D03*
X80940Y395989D03*
X85748Y475813D03*
X76100Y483400D03*
X77700Y502500D03*
X88573Y503935D03*
X88204Y543283D03*
X89200Y518700D03*
Y528500D03*
X65600Y543200D03*
X75600Y518600D03*
X88000Y613600D03*
X81000Y589000D03*
X78300Y637750D03*
X70020Y835051D03*
X90020D03*
X118577Y107902D03*
X104000Y128330D03*
X114364Y122054D03*
X118500Y176500D03*
Y173000D03*
X100900Y173800D03*
X116000Y207000D03*
Y202000D03*
X118500Y188500D03*
X116000Y192000D03*
Y196500D03*
X118500Y185000D03*
Y181000D03*
X104100Y194600D03*
X103700Y200800D03*
X116000Y211500D03*
X131700Y275700D03*
X109600Y276850D03*
X112732Y272786D03*
X125100Y282500D03*
X131700Y280000D03*
X108500Y284000D03*
X107213Y301192D03*
X101630Y312236D03*
X106717Y335600D03*
X122645Y367966D03*
X115951Y384138D03*
X111950Y392050D03*
X104204Y383661D03*
X129500Y412400D03*
X116235Y444665D03*
X103179Y423267D03*
X103176Y434180D03*
X127996Y535781D03*
X102000Y602500D03*
X101750Y595600D03*
X109051Y645936D03*
X124150Y707050D03*
X108200Y775800D03*
X112700Y775300D03*
Y770800D03*
X108200D03*
X103700D03*
Y775800D03*
Y766300D03*
X108200D03*
X112700D03*
X109900Y828800D03*
X105400Y828700D03*
X103200Y825400D03*
X115500Y825500D03*
X107600D03*
X120000Y843500D03*
X126500Y878200D03*
Y871000D03*
X129000Y875000D03*
X117500Y878200D03*
X122000D03*
X124500Y875000D03*
X120000Y865000D03*
Y875000D03*
Y853500D03*
X138577Y107902D03*
X158577D03*
X162500Y173500D03*
X146105Y403610D03*
X137000Y454700D03*
X134270Y504272D03*
X146869Y494823D03*
X153168D03*
X159467D03*
X134270Y516869D03*
X159467Y529469D03*
X160500Y689500D03*
X150000Y701500D03*
X142500Y709000D03*
X137000Y715500D03*
X150500Y804000D03*
X138500Y835000D03*
X137600Y839500D03*
X141100Y824500D03*
X141000Y830700D03*
X145900Y824400D03*
X142500Y862500D03*
Y867500D03*
Y872500D03*
X138500Y869500D03*
Y875200D03*
X141000Y877700D03*
X145500D03*
X149700D03*
X142500Y856500D03*
X159449Y878276D03*
X178577Y107902D03*
X181738Y122711D03*
X191800Y189600D03*
X177550Y407850D03*
X197850Y437450D03*
X175912Y450747D03*
X166534Y450821D03*
X186675Y453505D03*
X168916Y504272D03*
Y516870D03*
X184665Y520019D03*
X178365Y526319D03*
X185500Y577300D03*
X175660Y797340D03*
X174000Y804000D03*
X195000Y824090D03*
X188572Y832186D03*
X196474Y832178D03*
X196000Y868700D03*
X176771Y878276D03*
X195669D03*
X168898Y878200D03*
X185500D03*
X227669Y5500D03*
X210028Y12605D03*
Y32605D03*
Y52605D03*
Y72605D03*
X226533Y72591D03*
X228121Y63589D03*
X210028Y92605D03*
X227989Y83589D03*
X228007Y123787D03*
X233537Y160630D03*
X223000Y184000D03*
Y188500D03*
X225000Y192500D03*
X229200D03*
X210484Y179525D03*
X205750Y408250D03*
X205200Y442900D03*
X220897Y441833D03*
X220800Y446000D03*
X230572Y455128D03*
X219800Y493700D03*
X218906Y483186D03*
X216300Y546350D03*
X222300Y577300D03*
X216563Y555908D03*
X203124Y824090D03*
X233650Y827374D03*
X208700Y828000D03*
X201641Y827947D03*
X214380Y827374D03*
X221052D03*
X226978D03*
X201500Y868700D03*
X233464Y878276D03*
X208267D03*
X201969D03*
X220866D03*
X214567D03*
X227166D03*
X247669Y5500D03*
X258159Y73589D03*
X257851Y63589D03*
X257769Y83589D03*
X248160Y343140D03*
X262900Y438700D03*
X246375Y440725D03*
X265100Y443300D03*
X235850Y455050D03*
X243200Y508000D03*
X250200Y506600D03*
X264522Y511690D03*
X236100Y517100D03*
X255738Y574238D03*
X266906Y775531D03*
X249025Y827374D03*
X255697D03*
X261624D03*
X261811Y878276D03*
X249212D03*
X239764D03*
X255511D03*
X267669Y5500D03*
X286000Y143800D03*
X277300Y304800D03*
X297090Y311350D03*
X297729Y351029D03*
X285800Y460810D03*
X286169Y502000D03*
X285776Y489300D03*
X272860Y489147D03*
X297750Y592750D03*
X281800Y638900D03*
X288400Y626100D03*
Y634200D03*
X292500Y630200D03*
X281500Y748500D03*
X282378Y775431D03*
X298500Y752000D03*
X272116Y755592D03*
X298400Y775700D03*
X268296Y827374D03*
X280894D03*
X274222D03*
X286800Y863300D03*
X280800Y863500D03*
X268110Y878276D03*
X280708D03*
X287008D03*
X274410D03*
X329500Y192500D03*
X328000Y197400D03*
X334500Y197500D03*
Y192500D03*
X310839Y344339D03*
X315300Y344500D03*
X301929Y351100D03*
X305500Y483550D03*
X313452Y753856D03*
X330000Y754000D03*
X312017Y827374D03*
X318689D03*
X324616D03*
X331288D03*
X306500Y868700D03*
X312000Y868600D03*
X324803Y878276D03*
X331102D03*
X318503D03*
X312500Y878200D03*
X354800Y171400D03*
X358300D03*
X354800Y166900D03*
X358300D03*
X354800Y162400D03*
X358300D03*
X362300D03*
Y166900D03*
Y171400D03*
X344000Y197500D03*
X339500D03*
X344000Y192500D03*
X339500D03*
X354800Y181900D03*
X358300D03*
X354800Y176900D03*
X358300D03*
X362300D03*
Y181900D03*
X366792Y734171D03*
X364275Y723033D03*
X359500Y727335D03*
X349813Y827374D03*
X356485D03*
X362411D03*
X343886D03*
X337214D03*
X362599Y878276D03*
X356299D03*
X350000D03*
X343700D03*
X337402D03*
X387669Y5500D03*
X374275Y722919D03*
X369083Y827374D03*
X384459D03*
X391131D03*
X397057D03*
X378346Y878276D03*
X390944D03*
X397244D03*
X384646D03*
X370500Y878200D03*
X407669Y5500D03*
X427669D03*
X433400Y176800D03*
X416328Y827374D03*
X428926D03*
X422254D03*
X403729D03*
X409656D03*
X416141Y878276D03*
X431889D03*
X422441D03*
X403543D03*
X409843D03*
X447669Y5500D03*
X467669D03*
X466000Y62300D03*
X457700D03*
X454926Y118791D03*
X455800Y110200D03*
Y208300D03*
X456335Y835051D03*
X444500Y864450D03*
X438189Y878276D03*
X489261Y-14185D03*
X474400Y62300D03*
X483250Y59480D03*
X479700Y90100D03*
X491466Y126683D03*
X474990Y122660D03*
X494800Y162900D03*
X493186Y272414D03*
X501867Y295490D03*
X487906Y768598D03*
X491906Y768531D03*
X496061Y781678D03*
X494582Y800500D03*
X483500Y784650D03*
X485300Y808250D03*
X496335Y835051D03*
X480406Y827531D03*
X495878Y827431D03*
X514309Y52087D03*
X530057Y67048D03*
Y52087D03*
X530400Y72400D03*
X524000Y43500D03*
X532500Y62900D03*
X536100Y56700D03*
X530057Y106457D03*
Y96969D03*
Y82008D03*
X531400Y102900D03*
X522700D03*
X528700Y91100D03*
X531200Y87900D03*
X535400Y87400D03*
X532900Y92400D03*
X532400Y78200D03*
X521465Y140964D03*
X513876D03*
X532110Y138400D03*
X525000D03*
X506006Y126183D03*
X515348Y163101D03*
X515354Y168998D03*
X505100Y164800D03*
X512600Y186500D03*
X534481Y243676D03*
X518277Y288680D03*
X532921Y298436D03*
X527700Y587500D03*
X522500Y782031D03*
X535178Y781000D03*
X511800Y768300D03*
X528100Y767300D03*
X526274Y806000D03*
X511500Y803000D03*
X533800Y835500D03*
X527941Y864680D03*
X557616Y52087D03*
X538915Y67048D03*
X547773D03*
Y52087D03*
X538915D03*
X541200Y73400D03*
X541600Y62600D03*
X544500Y57400D03*
X546800Y46300D03*
X566700Y48700D03*
X570900Y56200D03*
X547773Y106457D03*
X538915Y96969D03*
X547773D03*
X538915Y82008D03*
X547773D03*
X537400Y91000D03*
X540100Y102900D03*
X541700Y92300D03*
X544600Y87300D03*
X538800Y76900D03*
X546800Y76200D03*
X566100Y103100D03*
X543000Y76300D03*
X539031Y136200D03*
X547400Y136170D03*
X560633Y127988D03*
X552800Y140800D03*
X543900Y154800D03*
X550300D03*
X554149Y200229D03*
X541446Y222562D03*
X565063Y256608D03*
Y247608D03*
Y252108D03*
X560318Y267199D03*
Y272199D03*
X560418Y278299D03*
Y283799D03*
Y289299D03*
X560318Y295699D03*
X553563Y306108D03*
Y310608D03*
X562123Y319158D03*
X553455Y314807D03*
X553463Y319108D03*
X557863D03*
X560531Y358080D03*
X564100Y358100D03*
X561781Y346281D03*
X542500Y806000D03*
X550186Y827374D03*
X543514D03*
X568711D03*
X556113D03*
X562785D03*
X538000Y878200D03*
X550000Y878276D03*
X562598D03*
X568898D03*
X556300D03*
X544000Y878200D03*
X600923Y52087D03*
X573364D03*
X582222D03*
X591080D03*
X573364Y67048D03*
X582222D03*
X591080D03*
X590000Y46200D03*
X579900Y55800D03*
X588000Y57200D03*
X584600Y63200D03*
X575800Y63100D03*
X588000Y72200D03*
X579000Y72300D03*
X573800Y72400D03*
X591080Y106457D03*
X573364D03*
X582222Y82008D03*
X591080D03*
X573364D03*
Y96969D03*
X582222D03*
X591080D03*
X576800Y91600D03*
X584600Y78200D03*
X575500Y78500D03*
X588000Y87100D03*
X579000Y87200D03*
X584500Y93200D03*
X580700Y90900D03*
X572500Y91200D03*
X576300Y103300D03*
X585100D03*
X580800Y76000D03*
X574100Y87800D03*
X579200Y140400D03*
X583640Y140636D03*
X598240Y137800D03*
X572990Y140501D03*
X588955Y140600D03*
X591377Y125797D03*
X597846Y125623D03*
X593000Y152800D03*
X598300Y152850D03*
X597763Y242608D03*
X602763Y240858D03*
X597763Y231608D03*
Y235108D03*
Y239108D03*
X602763Y236608D03*
Y232108D03*
X587100Y234800D03*
X597763Y246108D03*
Y250108D03*
X602763Y245108D03*
Y249608D03*
X605063Y257608D03*
X604170Y337900D03*
X599100Y348700D03*
X597500Y352050D03*
X589500Y361000D03*
X581700Y360700D03*
X573900Y360600D03*
X603500Y371200D03*
X576800Y369200D03*
X584500Y462500D03*
X586900Y713200D03*
X593908Y827374D03*
X600580D03*
X587981D03*
X581309D03*
X575383D03*
X594095Y878276D03*
X600393D03*
X587795D03*
X575197D03*
X581497D03*
X616671Y52087D03*
X625529D03*
X634388D03*
X616671Y67048D03*
X625529D03*
X634388D03*
X631100Y72300D03*
X622100Y72400D03*
X628200Y62600D03*
X619200Y62800D03*
X614300Y55800D03*
X620838Y58628D03*
X634100Y46800D03*
X631300Y57100D03*
X616800Y72200D03*
X624700Y61400D03*
X634388Y106457D03*
X616671D03*
X625529Y82008D03*
X634388D03*
X616671D03*
Y96969D03*
X625529D03*
X634388D03*
X611100Y103300D03*
X619600D03*
X628300D03*
X615800Y91200D03*
X624400Y91100D03*
X628000Y93000D03*
X618300Y88000D03*
X628100Y77700D03*
X619400Y77500D03*
X631200Y87200D03*
X624000Y76000D03*
X621900Y87600D03*
X619700Y92100D03*
X629393Y140451D03*
X631940Y137800D03*
X607520Y137780D03*
X605924Y126398D03*
X633900Y149600D03*
X607763Y242608D03*
Y231608D03*
Y235108D03*
Y239108D03*
X619363Y225108D03*
X623363D03*
X611563Y278108D03*
X607763Y246108D03*
Y250108D03*
X607563Y265608D03*
X607463Y270608D03*
X607563Y261108D03*
X609063Y255608D03*
X607563Y276108D03*
Y282108D03*
Y287608D03*
Y293608D03*
X607519Y299497D03*
X611563Y290108D03*
Y284608D03*
X635350Y320850D03*
X606322Y351522D03*
X633000Y356600D03*
Y360500D03*
Y353000D03*
X636500Y356500D03*
X629500D03*
Y371000D03*
X626458Y372521D03*
X616706Y349718D03*
X618680Y346780D03*
X621300Y366900D03*
X609500Y360717D03*
X623000Y382500D03*
X617000D03*
X627600Y685000D03*
X608000Y700800D03*
X613178Y827374D03*
X606506D03*
X638375D03*
X631703D03*
X619105D03*
X625777D03*
X606693Y878276D03*
X619292D03*
X612992D03*
X625590D03*
X631890D03*
X644230Y52087D03*
X659978D03*
X668836D03*
X659978Y67048D03*
X668836D03*
X653300Y48600D03*
X665400Y72500D03*
X661100Y73000D03*
X662300Y63300D03*
X656700Y57400D03*
X665696Y57027D03*
X671100Y63400D03*
X659978Y106457D03*
X668836Y82008D03*
X659978D03*
Y96969D03*
X668836D03*
X656400Y102600D03*
X665100Y102700D03*
X660600Y93300D03*
X669400Y93200D03*
X659700Y86400D03*
X662400Y78100D03*
X667500Y76000D03*
X664000Y91100D03*
X671300Y78100D03*
X641159Y137800D03*
X643160Y149600D03*
X666593Y226677D03*
X662593Y223677D03*
X658093D03*
X671124Y210770D03*
X655500Y213500D03*
X670063Y274708D03*
X669633Y259148D03*
X672100Y299800D03*
X640532Y318099D03*
X643932Y318104D03*
X639500Y342500D03*
X652254Y336353D03*
X662897Y346873D03*
X663140Y353982D03*
X646884Y355616D03*
X639500Y371000D03*
X653000Y380500D03*
X644100Y488700D03*
X639500Y678500D03*
X657000Y714500D03*
X668500Y700000D03*
X648900Y782500D03*
X666348Y827374D03*
X653750D03*
X660422D03*
X653500Y819100D03*
X647838Y872000D03*
X660236Y878276D03*
X666536D03*
X654000Y878200D03*
X642200Y877900D03*
X687537Y52087D03*
X677695D03*
Y67048D03*
X674600Y72200D03*
X676800Y46300D03*
X677695Y106457D03*
Y82008D03*
Y96969D03*
X674300Y102400D03*
X678300Y93100D03*
X674800Y86800D03*
X704537Y221492D03*
X678063Y238108D03*
X673063D03*
X672927Y219677D03*
X677927D03*
X686063Y230108D03*
X696800Y237900D03*
X682763Y238008D03*
X686063Y224608D03*
X687253Y237878D03*
X691753D03*
X698300Y226500D03*
X693800D03*
X685115Y210677D03*
X689623Y269648D03*
X694963Y269608D03*
X689723Y274748D03*
X694223D03*
X679723D03*
X684223D03*
X690233Y255748D03*
X695000Y255800D03*
X690133Y260348D03*
X694633D03*
X680133Y259148D03*
X684633D03*
X674563Y274708D03*
X674133Y259148D03*
X677000Y299900D03*
X682063Y299108D03*
X683800Y295000D03*
X684063Y285908D03*
Y290408D03*
X689500Y344000D03*
X704500Y343000D03*
X676700Y378800D03*
X687000Y378700D03*
X678500Y684000D03*
X673020Y827374D03*
X698217D03*
X691545D03*
X678947D03*
X685619D03*
X698100Y821600D03*
X703900Y866100D03*
X697700D03*
X704331Y878276D03*
X698031D03*
X691733D03*
X685433D03*
X679134D03*
X672834D03*
X724018Y5719D03*
X707051Y12174D03*
X738384Y8232D03*
X723200Y42300D03*
X723501Y82680D03*
X723481Y76780D03*
X723610Y106430D03*
X723569Y100969D03*
X723659Y97292D03*
X723429Y91683D03*
X735157Y97005D03*
X735326Y102660D03*
X723438Y112700D03*
X723638Y118353D03*
X712337Y207792D03*
X712137Y213292D03*
Y219392D03*
X738800Y272000D03*
Y265500D03*
Y258000D03*
Y251500D03*
X706800Y272500D03*
Y265500D03*
Y258000D03*
Y252000D03*
X715300Y272000D03*
Y265500D03*
Y258000D03*
Y251500D03*
X724300Y272000D03*
Y265500D03*
Y258000D03*
Y251500D03*
X732300Y272000D03*
Y265500D03*
Y258000D03*
Y251500D03*
X707363Y298108D03*
X718863Y295908D03*
X714363D03*
X723363D03*
X732363D03*
X727863D03*
X724400Y626500D03*
X735640Y827374D03*
X723041D03*
X729713D03*
X729527Y878276D03*
X735827D03*
X723000Y878200D03*
X742290Y68550D03*
X750130Y63340D03*
X748300Y53800D03*
X772000Y64200D03*
X753500Y96600D03*
X762400Y127600D03*
X753500Y110900D03*
X769400Y111900D03*
X743500Y362000D03*
X753000Y359000D03*
X743000Y598000D03*
X773435Y827374D03*
X754910D03*
X748238D03*
X742312D03*
X760837D03*
X767509D03*
X754724Y878276D03*
X761024D03*
X767323D03*
X742126D03*
X748426D03*
X781500Y85100D03*
X797800Y104500D03*
X776538Y107162D03*
X773900Y138300D03*
X786033Y827374D03*
X780107D03*
X792705D03*
X798632D03*
X805304D03*
X779921Y878276D03*
X786221D03*
X792519D03*
X798819D03*
X805118D03*
X773623D03*
X821877Y21090D03*
X831125Y67775D03*
X833900Y467000D03*
X812500Y499400D03*
X836427Y827374D03*
X817902D03*
X811230D03*
X836615Y878276D03*
X830315D03*
X811418D03*
X820000Y878200D03*
X858500Y28000D03*
X858100Y21400D03*
X858500Y36000D03*
X847000Y9100D03*
X859000Y43500D03*
X871550Y56450D03*
X858800Y52200D03*
X844900Y85100D03*
X851500Y705500D03*
X852500Y718000D03*
X847500Y717500D03*
X857406Y745598D03*
X861406Y745531D03*
X855500Y775500D03*
X844150Y762150D03*
X858695Y759900D03*
X871000Y776500D03*
X849906Y804531D03*
X865378Y804431D03*
X851890Y789270D03*
X870900Y812104D03*
X855697Y827374D03*
X849025D03*
X843099D03*
X861823Y853696D03*
X849213Y878276D03*
X842913D03*
X856000Y878200D03*
X899769Y4355D03*
X896500Y9500D03*
X877500Y23600D03*
X900250Y38150D03*
X888474Y9173D03*
X900501Y48705D03*
X883700Y50700D03*
X890000Y97800D03*
X897000Y96700D03*
X894095Y131890D03*
X898032Y139764D03*
Y131890D03*
Y135827D03*
X905906Y124016D03*
Y120079D03*
Y116142D03*
X901969Y124016D03*
X894095D03*
X886221D03*
X878347D03*
X894095Y163386D03*
X898032D03*
Y167323D03*
Y171260D03*
Y175197D03*
X901969Y163386D03*
X905906D03*
X898032Y143701D03*
Y147638D03*
Y151575D03*
Y155512D03*
Y159449D03*
Y194881D03*
Y198818D03*
Y202755D03*
X894095D03*
X898032Y179134D03*
Y183071D03*
Y190944D03*
X905906Y183071D03*
X901969D03*
X898032Y238188D03*
X894095D03*
X898032Y234251D03*
Y230314D03*
X905906Y238188D03*
X901969D03*
X898032Y226377D03*
Y222440D03*
Y218503D03*
Y214566D03*
Y210629D03*
X907500Y325000D03*
X902500Y370000D03*
X897000Y370500D03*
X907500Y368000D03*
X900999Y748550D03*
X885400Y743600D03*
X900824Y781531D03*
X895278Y758885D03*
X874887Y759253D03*
X884671Y775500D03*
X885167Y816593D03*
X884412Y835051D03*
X911800Y37000D03*
X938000Y30300D03*
X919400Y33300D03*
X926500Y60050D03*
X935000Y97400D03*
X927100Y96900D03*
X937402Y175197D03*
X941339Y171260D03*
X937402Y167323D03*
X941339Y163386D03*
X929528Y175197D03*
X933465Y171260D03*
X929528Y167323D03*
X933465Y163386D03*
X925591Y171260D03*
X921654Y175197D03*
X925591Y163386D03*
X921654Y167323D03*
X917717Y163386D03*
Y171260D03*
X921654Y159449D03*
Y194881D03*
X917717Y198818D03*
X937402Y194881D03*
X933465Y198818D03*
X929528Y202755D03*
X925591Y206692D03*
X929528Y194881D03*
X925591Y198818D03*
X921654Y202755D03*
X917717Y206692D03*
X933465D03*
X937402Y202755D03*
X941339Y198818D03*
Y206692D03*
X925591Y190944D03*
X933465Y179134D03*
X929528Y183071D03*
X925591Y179134D03*
X921654Y183071D03*
X941339Y190944D03*
X933465D03*
X937402Y183071D03*
X941339Y179134D03*
X917717Y190944D03*
X921654Y238188D03*
X917717D03*
Y214566D03*
X913780Y238188D03*
X909843D03*
X921654Y210629D03*
X925591Y214566D03*
X929528Y210629D03*
X941339Y214566D03*
X933465D03*
X937402Y210629D03*
X909500Y338000D03*
X909000Y353600D03*
X908700Y347300D03*
X938898Y640169D03*
X916319Y678588D03*
Y658588D03*
Y698588D03*
Y738588D03*
Y718588D03*
Y778588D03*
Y758588D03*
Y798588D03*
Y818588D03*
X974100Y19600D03*
X952500Y75100D03*
X947900Y67900D03*
X949500Y97500D03*
X949212Y167323D03*
X964960D03*
X968897Y163386D03*
X957086Y175197D03*
X961023Y171260D03*
X953149D03*
X949212Y175197D03*
X961023Y163386D03*
X957086Y167323D03*
X972834D03*
X968897Y171260D03*
X964960Y175197D03*
X972834D03*
X949212Y194881D03*
X968897Y198818D03*
X964960Y202755D03*
X961023Y206692D03*
X972834Y194881D03*
X953149Y206692D03*
X964960Y194881D03*
X961023Y198818D03*
X957086Y202755D03*
X949212D03*
X953149Y198818D03*
X957086Y194881D03*
X972834Y202755D03*
X968897Y206692D03*
X949212Y183071D03*
X953149Y179134D03*
X961023D03*
X957086Y183071D03*
X953149Y190944D03*
X968897D03*
X972834Y183071D03*
X961023Y190944D03*
X964960Y183071D03*
X968897Y179134D03*
X972834Y238188D03*
X953149Y214566D03*
X957086Y210629D03*
X949212D03*
X972834D03*
X968897Y214566D03*
X961023D03*
X964960Y210629D03*
X957800Y570300D03*
X958898Y640169D03*
X976771Y163386D03*
Y171260D03*
Y206692D03*
Y198818D03*
Y190944D03*
X992519Y238188D03*
X988582D03*
X984645D03*
X980708D03*
X1000393D03*
X996456D03*
Y234251D03*
Y230314D03*
Y226377D03*
Y222440D03*
Y218503D03*
X976771Y238188D03*
X978898Y640169D03*
X994248Y665818D03*
Y685818D03*
Y705818D03*
Y745818D03*
Y725818D03*
Y765818D03*
Y805818D03*
Y785818D03*
X1040121Y26870D03*
X1039822Y35743D03*
X1017908Y41556D03*
X1018900Y14198D03*
X1010975Y29017D03*
X1029553Y13981D03*
X1011300Y53000D03*
X1024318Y51554D03*
X1014700Y53700D03*
X1028500Y257500D03*
X1012600Y476700D03*
X1017800Y572700D03*
X1043300Y631300D03*
X1041500Y682000D03*
X1041900Y658100D03*
X1039577Y827374D03*
X1024004Y855893D03*
X1033464Y878276D03*
X1039764D03*
X1069261Y-14185D03*
X1049261D03*
X1045850Y6228D03*
X1062088Y40597D03*
X1072804Y19894D03*
X1064900Y10400D03*
X1050875Y61090D03*
X1057259Y77276D03*
X1047000Y644000D03*
X1045000Y617500D03*
X1067000Y711000D03*
X1062500Y738000D03*
X1058500Y758000D03*
X1058847Y827374D03*
X1052175D03*
X1046249D03*
X1064774D03*
X1071446D03*
X1046063Y878276D03*
X1071260D03*
X1064961D03*
X1058661D03*
X1052363D03*
X1089261Y-14185D03*
X1103424Y67690D03*
X1077432Y64225D03*
X1110664Y78483D03*
X1103253Y76910D03*
X1079500Y631000D03*
X1080000Y650500D03*
X1081000Y670000D03*
X1084044Y827374D03*
X1077372D03*
X1102569D03*
X1109241D03*
X1089970D03*
X1096642D03*
X1090158Y878276D03*
X1083858D03*
X1077560D03*
X1096456D03*
X1102756D03*
X1109055D03*
X1116671Y-315D03*
Y52087D03*
X1132419Y67048D03*
X1141277D03*
Y52087D03*
X1132419D03*
X1127300Y46300D03*
X1122800Y55100D03*
X1132100Y56300D03*
X1131900Y70700D03*
X1140900Y71100D03*
X1141900Y63300D03*
X1132419Y106457D03*
Y96969D03*
X1141277D03*
X1132419Y82008D03*
X1141277D03*
X1142418Y78638D03*
X1131800Y85600D03*
X1141200Y86800D03*
X1126400Y92200D03*
X1143500Y93300D03*
X1123000Y99200D03*
X1131880Y100377D03*
X1134800Y93300D03*
X1116933Y85243D03*
X1140364Y827374D03*
X1121839D03*
X1115167D03*
X1127766D03*
X1134438D03*
X1140552Y878276D03*
X1115355D03*
X1127953D03*
X1134252D03*
X1121653D03*
X1159978Y-315D03*
Y52087D03*
X1175726D03*
Y67048D03*
X1150135D03*
Y52087D03*
X1175300Y71100D03*
X1175100Y55700D03*
X1166500Y56200D03*
X1171700Y45900D03*
X1149100Y46300D03*
X1150700Y63300D03*
X1175726Y106457D03*
X1150135D03*
X1175726Y82008D03*
Y96969D03*
X1150135D03*
Y82008D03*
X1148900Y75900D03*
X1168400Y103000D03*
X1177000Y102800D03*
X1176200Y92900D03*
X1178100Y78000D03*
X1175200Y85900D03*
X1151492Y78668D03*
X1164857Y138505D03*
X1175851Y142410D03*
X1177600Y241200D03*
X1173400D03*
X1166400Y234300D03*
X1170600D03*
X1175700D03*
X1177200Y248200D03*
X1173000D03*
X1177300Y254400D03*
X1173100D03*
X1176300Y261500D03*
X1171200D03*
X1167000D03*
X1161700Y818500D03*
X1159634Y827374D03*
X1152962D03*
X1147036D03*
X1175010D03*
X1174900Y818300D03*
X1159448Y878276D03*
X1153150D03*
X1173623Y878200D03*
X1146850Y878276D03*
X1165748D03*
X1203285Y-315D03*
Y52087D03*
X1184584D03*
X1193442D03*
X1184584Y67048D03*
X1193442D03*
X1185200Y72600D03*
X1210511Y52300D03*
X1193555Y61875D03*
X1183884Y61598D03*
X1188200Y61600D03*
X1192300Y46100D03*
X1184100Y56100D03*
X1193442Y106457D03*
X1184584Y82008D03*
X1193442D03*
X1184584Y96969D03*
X1193442D03*
X1193900Y78000D03*
X1211500Y102900D03*
X1194000Y93200D03*
X1185800Y102900D03*
X1185100Y93000D03*
X1187100Y77900D03*
X1184800Y87200D03*
X1202410Y142850D03*
X1193845Y137855D03*
X1184629Y137740D03*
X1185070Y142384D03*
X1210391Y156730D03*
X1200391Y156779D03*
X1193192Y142970D03*
X1203100Y241100D03*
X1198900D03*
X1207900D03*
X1182400Y241200D03*
X1197900Y234300D03*
X1207400D03*
X1203200D03*
X1179900D03*
X1188900D03*
X1184700D03*
X1193700D03*
X1182000Y248200D03*
X1202600Y254100D03*
X1198400D03*
X1207400D03*
X1202500Y247500D03*
X1198300D03*
X1207300D03*
X1182100Y254400D03*
X1203800Y261500D03*
X1208000D03*
X1194300D03*
X1198500D03*
X1185300D03*
X1189500D03*
X1180500D03*
X1205500Y334400D03*
X1194280Y827374D03*
X1187608D03*
X1181682D03*
X1200735Y864273D03*
X1194063D03*
X1200394Y878276D03*
X1194094D03*
X1187796D03*
X1181496D03*
X1246592Y-315D03*
Y52087D03*
X1219033D03*
X1227891D03*
X1236750D03*
X1219033Y67048D03*
X1227891D03*
X1236750D03*
X1231400Y58300D03*
X1215400Y57600D03*
X1216300Y72900D03*
X1235800Y46400D03*
X1228000Y57000D03*
X1218600Y56000D03*
X1214700Y46000D03*
X1221200Y63400D03*
X1230300Y63200D03*
X1228900Y72900D03*
X1236750Y106457D03*
X1219033D03*
X1227891Y82008D03*
X1236750D03*
X1219033D03*
Y96969D03*
X1227891D03*
X1236750D03*
X1230000Y78800D03*
X1221300Y78400D03*
X1219200Y87000D03*
X1229100Y87900D03*
X1232500Y90900D03*
X1229900Y103100D03*
X1228300Y93100D03*
X1219500Y93300D03*
X1220100Y102700D03*
X1219138Y137928D03*
X1227999Y142465D03*
X1236692Y137720D03*
X1237219Y142420D03*
X1228359Y137960D03*
X1229000Y210500D03*
X1242500Y209000D03*
X1232000Y194500D03*
X1237000D03*
X1226500Y201500D03*
Y194500D03*
X1244500D03*
X1212900Y234300D03*
X1233900Y240700D03*
X1239900D03*
X1244900D03*
X1228900D03*
X1228500Y235000D03*
X1234000D03*
X1240000D03*
X1245000D03*
X1214000Y261500D03*
X1233800Y246600D03*
X1239800D03*
X1244800D03*
X1228800D03*
X1229000Y252000D03*
X1245000D03*
X1240000D03*
X1234000D03*
X1226000Y261300D03*
X1227000Y279000D03*
X1242000D03*
X1232000Y292000D03*
X1237000D03*
X1227000Y285500D03*
X1244500Y292000D03*
X1242000Y343000D03*
X1235400Y364400D03*
X1213400Y355400D03*
X1214100Y469800D03*
X1237800Y524500D03*
X1232300Y568900D03*
X1238375Y827374D03*
X1231703D03*
X1219105D03*
X1225777D03*
X1244302D03*
X1217717Y878076D03*
X1225590Y878276D03*
X1231890D03*
X1244489D03*
X1238189D03*
X1262340Y52087D03*
X1271198D03*
X1280057D03*
X1262340Y67048D03*
X1271198D03*
X1280057D03*
X1261900Y71039D03*
X1265500Y61900D03*
X1272200Y72900D03*
X1275200Y61200D03*
X1269900Y61100D03*
X1279100Y46300D03*
X1272200Y57900D03*
X1258400Y45900D03*
X1254500Y51100D03*
X1280057Y106457D03*
X1262340D03*
X1271198Y82008D03*
X1280057D03*
X1262340D03*
Y96969D03*
X1271198D03*
X1280057D03*
X1271300Y77100D03*
X1273200Y103200D03*
X1256000Y103300D03*
X1263200Y102700D03*
X1270300Y91100D03*
X1262800Y93100D03*
X1254200Y96300D03*
X1275500Y91000D03*
X1272700Y88000D03*
X1265200Y77400D03*
X1261900Y86000D03*
X1275800Y75900D03*
X1252768Y141181D03*
X1278160Y140547D03*
X1257899Y142881D03*
X1245910Y137810D03*
X1273068Y140514D03*
X1262880Y142909D03*
X1247500Y209000D03*
X1252500Y194500D03*
X1263000Y210307D03*
X1257500Y194500D03*
X1263000Y202000D03*
X1262500Y194500D03*
X1255900Y240700D03*
X1249900D03*
X1262500Y235000D03*
X1250000D03*
X1256000D03*
X1255800Y246600D03*
X1249800D03*
X1275500Y264500D03*
X1262000Y252000D03*
X1256000D03*
X1250000D03*
X1247000Y279000D03*
X1262500Y279500D03*
X1252000Y292000D03*
X1257000D03*
X1262500Y286000D03*
X1258500Y335500D03*
X1266500D03*
X1273500Y397000D03*
X1257500D03*
X1254000D03*
X1259200Y471800D03*
X1259000Y680000D03*
X1265000Y672000D03*
X1253500D03*
X1278000Y689000D03*
X1263572Y827374D03*
X1269498D03*
X1276170D03*
X1256900D03*
X1250974D03*
X1263386Y878276D03*
X1275984D03*
X1257087D03*
X1269686D03*
X1250787D03*
X1289899Y-315D03*
Y52087D03*
X1291660Y140257D03*
X1297360Y140172D03*
X1301749Y125479D03*
X1282189Y144361D03*
X1287637Y144386D03*
X1297668Y155524D03*
X1290870Y186285D03*
X1311181Y186548D03*
X1297500Y351800D03*
X1291600Y495200D03*
X1294700Y593400D03*
X1302128Y674067D03*
X1306128Y674000D03*
X1285000Y694000D03*
X1280500Y706000D03*
X1310376Y687205D03*
X1301728Y711200D03*
X1310100Y732900D03*
X1294628Y733000D03*
X1304800Y811900D03*
X1288768Y827374D03*
X1282096D03*
X1307294D03*
X1301800Y878100D03*
X1294268Y872169D03*
X1288582Y878276D03*
X1282284D03*
X1307481D03*
X1324845Y130527D03*
X1325429Y148270D03*
X1327782Y192579D03*
Y200579D03*
Y207579D03*
X1328411Y237679D03*
X1327782Y215579D03*
Y221579D03*
X1327841Y228639D03*
X1332683Y240409D03*
X1328356Y242091D03*
X1328317Y246291D03*
X1332683Y244609D03*
Y248809D03*
X1337000Y263250D03*
X1332000Y261500D03*
Y265000D03*
Y268500D03*
Y272500D03*
Y257500D03*
Y254000D03*
X1342000D03*
Y257500D03*
Y261500D03*
Y265000D03*
Y268500D03*
Y272500D03*
X1337000Y267500D03*
Y272000D03*
Y259000D03*
Y254500D03*
X1322250Y282250D03*
X1345850Y676750D03*
X1326250Y669550D03*
X1333500Y709500D03*
X1323076Y686999D03*
X1338200Y689800D03*
X1315546Y709500D03*
X1341400Y686900D03*
X1326661Y740700D03*
X1345088Y827374D03*
X1332490D03*
X1339162D03*
X1326564D03*
X1319892D03*
X1313966D03*
X1320079Y878276D03*
X1345276D03*
X1332678D03*
X1338976D03*
X1326378D03*
X1313779D03*
X1368028Y175745D03*
X1378115Y189144D03*
X1374000Y192500D03*
Y188300D03*
Y196700D03*
X1378500Y198000D03*
X1378115Y193344D03*
X1369300Y259300D03*
X1363900Y537600D03*
X1361800Y596800D03*
X1358700Y655700D03*
X1348500Y713000D03*
X1377000Y725000D03*
X1378000Y806900D03*
X1369925Y835051D03*
X1351760Y827374D03*
X1357886Y864246D03*
X1352200Y878400D03*
X1394500Y139626D03*
Y119626D03*
Y159626D03*
Y199626D03*
Y179626D03*
X1381568Y180579D03*
X1382500Y193500D03*
Y188000D03*
X1394500Y239626D03*
Y219626D03*
Y259626D03*
Y299626D03*
Y279626D03*
Y339626D03*
Y319626D03*
Y359626D03*
Y399626D03*
Y379626D03*
Y439626D03*
Y419626D03*
Y479626D03*
Y459626D03*
Y499626D03*
Y539626D03*
Y519626D03*
Y579626D03*
Y559626D03*
Y599626D03*
Y639626D03*
Y619626D03*
Y679626D03*
Y659626D03*
Y699626D03*
Y739626D03*
Y719626D03*
Y759626D03*
Y779626D03*
Y799626D03*
Y819626D03*
X1389925Y835051D03*
G54D33*
X501742Y215594D03*
G54D10*
X700Y19100D03*
X16200Y120100D03*
X27200Y821800D03*
X33800Y872600D03*
X1384200Y122800D03*
X1373200Y823500D03*
X1415100Y-36700D03*
X1389800Y879000D03*
G54D16*
X39370Y801181D03*
X1360630Y135826D03*
Y801181D03*
G54D19*
X54378Y237402D03*
G54D22*
X122165Y142874D03*
X173897D03*
G54D17*
X42587Y151614D03*
X80579D03*
G54D30*
X336417Y21260D03*
X293110Y55906D03*
X336417Y90551D03*
X789850Y236220D03*
Y283464D03*
X1376968Y21260D03*
X1333661Y55906D03*
X1376968Y90551D03*
G54D15*
X25050Y716900D03*
X534481Y286876D03*
G54D20*
X38500Y321400D03*
G54D35*
X535962Y37520D03*
X579269D03*
X622577D03*
X665884D03*
X1138324D03*
X1181631D03*
X1224939D03*
X1268246D03*
G54D27*
X161811Y153543D03*
%LPC*%
G75*
G54D40*
G01X145579Y-328699D02*
Y-346199D01*
X154313D01*
G01X167446Y-334533D02*
Y-346199D01*
G01Y-329866D02*
X167009Y-329574D01*
Y-328991D01*
X167446Y-328699D01*
X167883Y-328991D01*
Y-329574D01*
X167446Y-329866D01*
G01X181889Y-350574D02*
X183418Y-351741D01*
X185164Y-352032D01*
X186692Y-351741D01*
X188003Y-350283D01*
X188876Y-348241D01*
Y-334533D01*
G01Y-336866D02*
X188003Y-335699D01*
X186692Y-334824D01*
X185164Y-334533D01*
X183418Y-335116D01*
X182326Y-336282D01*
X181452Y-338324D01*
X181016Y-340366D01*
X181234Y-342116D01*
X182108Y-344158D01*
X183418Y-345616D01*
X185164Y-346199D01*
X186474Y-345907D01*
X188003Y-344741D01*
X188876Y-343575D01*
G01X198734Y-346199D02*
Y-328699D01*
G01Y-337157D02*
X199826Y-335699D01*
X200918Y-334824D01*
X202664Y-334533D01*
X203974Y-334824D01*
X205503Y-335991D01*
X206158Y-337741D01*
Y-346199D01*
G01X219946Y-328699D02*
Y-346199D01*
G01X216889Y-334533D02*
X223003D01*
G01X233734Y-346199D02*
Y-334533D01*
G01Y-337449D02*
X234608Y-335991D01*
X235918Y-334824D01*
X237664Y-334533D01*
X239192Y-334824D01*
X240503Y-335991D01*
X241158Y-338032D01*
Y-346199D01*
G01X254946Y-334533D02*
Y-346199D01*
G01Y-329866D02*
X254509Y-329574D01*
Y-328991D01*
X254946Y-328699D01*
X255383Y-328991D01*
Y-329574D01*
X254946Y-329866D01*
G01X268734Y-346199D02*
Y-334533D01*
G01Y-337449D02*
X269608Y-335991D01*
X270918Y-334824D01*
X272664Y-334533D01*
X274192Y-334824D01*
X275503Y-335991D01*
X276158Y-338032D01*
Y-346199D01*
G01X286889Y-350574D02*
X288418Y-351741D01*
X290164Y-352032D01*
X291692Y-351741D01*
X293003Y-350283D01*
X293876Y-348241D01*
Y-334533D01*
G01Y-336866D02*
X293003Y-335699D01*
X291692Y-334824D01*
X290164Y-334533D01*
X288418Y-335116D01*
X287326Y-336282D01*
X286452Y-338324D01*
X286016Y-340366D01*
X286234Y-342116D01*
X287108Y-344158D01*
X288418Y-345616D01*
X290164Y-346199D01*
X291474Y-345907D01*
X293003Y-344741D01*
X293876Y-343575D01*
G01X320579Y-346199D02*
Y-328699D01*
X325819D01*
X327566Y-329574D01*
X328876Y-331616D01*
X329313Y-333949D01*
X328876Y-336282D01*
X327784Y-338032D01*
X325819Y-338908D01*
X320579D01*
G01X346813Y-346199D02*
X338079D01*
Y-328699D01*
X346813D01*
G01X343319Y-337157D02*
X338079D01*
G01X361692Y-336866D02*
X362566Y-335991D01*
X363221Y-334533D01*
X363658Y-332490D01*
X363221Y-330741D01*
X362348Y-329574D01*
X360819Y-328699D01*
X354924D01*
Y-346199D01*
X362129D01*
X363658Y-345033D01*
X364531Y-343282D01*
X364968Y-341241D01*
X364531Y-339199D01*
X363221Y-337449D01*
X361692Y-336866D01*
X354924D01*
G01X390579Y-346199D02*
Y-328699D01*
X395819D01*
X397566Y-329574D01*
X398876Y-331616D01*
X399313Y-333949D01*
X398876Y-336282D01*
X397784Y-338032D01*
X395819Y-338908D01*
X390579D01*
G01X406769Y-346199D02*
Y-328699D01*
X412446Y-343282D01*
X418123Y-328699D01*
Y-346199D01*
G01X434749Y-330158D02*
X433439Y-329282D01*
X431911Y-328699D01*
X430164D01*
X428199Y-329574D01*
X426671Y-331032D01*
X425579Y-332783D01*
X424706Y-335699D01*
X424487Y-338324D01*
X424924Y-340949D01*
X425579Y-342699D01*
X426889Y-344449D01*
X428418Y-345616D01*
X429946Y-346199D01*
X431474D01*
X433003Y-345616D01*
X434313Y-344741D01*
X435405Y-343575D01*
G01X460579Y-346199D02*
Y-328699D01*
X465819D01*
X467566Y-329574D01*
X468876Y-331616D01*
X469313Y-333949D01*
X468876Y-336282D01*
X467784Y-338032D01*
X465819Y-338908D01*
X460579D01*
G01X476987Y-328699D02*
X482446Y-346199D01*
X487905Y-328699D01*
G01X499946D02*
Y-346199D01*
G01X494924Y-328699D02*
X504968D01*
G01X284269Y-301199D02*
Y-283699D01*
X289946Y-298282D01*
X295623Y-283699D01*
Y-301199D01*
G01X307446D02*
X306136Y-300907D01*
X304826Y-299741D01*
X303952Y-297699D01*
X303516Y-295366D01*
X303952Y-293032D01*
X304826Y-290991D01*
X306136Y-289824D01*
X307446Y-289533D01*
X308756Y-289824D01*
X310066Y-290991D01*
X310939Y-293032D01*
X311158Y-295366D01*
X310939Y-297699D01*
X310066Y-299741D01*
X308756Y-300907D01*
X307446Y-301199D01*
G01X328876Y-283699D02*
Y-301199D01*
G01Y-298575D02*
X328003Y-300033D01*
X326692Y-300907D01*
X325164Y-301199D01*
X323418Y-300616D01*
X322108Y-299158D01*
X321234Y-297408D01*
X321016Y-295366D01*
X321234Y-293324D01*
X322108Y-291574D01*
X323418Y-290116D01*
X325164Y-289533D01*
X326692Y-289824D01*
X327784Y-290408D01*
X328876Y-291574D01*
G01X339171Y-293324D02*
X346158D01*
X345503Y-291282D01*
X344411Y-290116D01*
X342883Y-289533D01*
X341354Y-289824D01*
X340044Y-290699D01*
X339171Y-292741D01*
X338734Y-294491D01*
Y-296241D01*
X339171Y-297991D01*
X340263Y-299741D01*
X341573Y-300907D01*
X343101Y-301199D01*
X344629Y-300616D01*
X346158Y-298866D01*
G01X359946Y-301199D02*
Y-283699D01*
G01X556346Y-346199D02*
Y-328699D01*
X553726Y-332199D01*
G01Y-346199D02*
X558966D01*
G01X569043Y-343575D02*
X570352Y-345033D01*
X571881Y-345907D01*
X573846Y-346199D01*
X575811Y-345616D01*
X577339Y-344449D01*
X578431Y-342408D01*
X578649Y-340074D01*
X578213Y-337741D01*
X577121Y-336282D01*
X575592Y-335116D01*
X574064Y-334824D01*
X572536Y-335116D01*
X570571Y-336282D01*
X571226Y-328699D01*
X577121D01*
G01X591346Y-346199D02*
Y-328699D01*
X588726Y-332199D01*
G01Y-346199D02*
X593966D01*
G01X608846Y-328699D02*
X607099Y-329282D01*
X605789Y-330741D01*
X604916Y-332490D01*
X604261Y-334824D01*
X604043Y-337449D01*
X604261Y-340074D01*
X604916Y-342408D01*
X605789Y-344158D01*
X607099Y-345616D01*
X608846Y-346199D01*
X610592Y-345616D01*
X611903Y-344158D01*
X612776Y-342408D01*
X613431Y-340074D01*
X613649Y-337449D01*
X613431Y-334824D01*
X612776Y-332490D01*
X611903Y-330741D01*
X610592Y-329282D01*
X608846Y-328699D01*
G01X621543Y-343575D02*
X622852Y-345033D01*
X624381Y-345907D01*
X626346Y-346199D01*
X628311Y-345616D01*
X629839Y-344449D01*
X630931Y-342408D01*
X631149Y-340074D01*
X630713Y-337741D01*
X629621Y-336282D01*
X628092Y-335116D01*
X626564Y-334824D01*
X625036Y-335116D01*
X623071Y-336282D01*
X623726Y-328699D01*
X629621D01*
G01X543229Y-301199D02*
Y-283699D01*
X548469D01*
X550216Y-284574D01*
X551526Y-286616D01*
X551963Y-288949D01*
X551526Y-291282D01*
X550434Y-293032D01*
X548469Y-293908D01*
X543229D01*
G01X569899Y-285158D02*
X568589Y-284282D01*
X567061Y-283699D01*
X565314D01*
X563349Y-284574D01*
X561821Y-286032D01*
X560729Y-287783D01*
X559856Y-290699D01*
X559637Y-293324D01*
X560074Y-295949D01*
X560729Y-297699D01*
X562039Y-299449D01*
X563568Y-300616D01*
X565096Y-301199D01*
X566624D01*
X568153Y-300616D01*
X569463Y-299741D01*
X570555Y-298575D01*
G01X584342Y-291866D02*
X585216Y-290991D01*
X585871Y-289533D01*
X586308Y-287490D01*
X585871Y-285741D01*
X584998Y-284574D01*
X583469Y-283699D01*
X577574D01*
Y-301199D01*
X584779D01*
X586308Y-300033D01*
X587181Y-298282D01*
X587618Y-296241D01*
X587181Y-294199D01*
X585871Y-292449D01*
X584342Y-291866D01*
X577574D01*
G01X593546Y-307032D02*
X606646D01*
G01X612574Y-301199D02*
Y-283699D01*
X622618Y-301199D01*
Y-283699D01*
G01X635096Y-301199D02*
X633349Y-300907D01*
X631821Y-299741D01*
X630511Y-297991D01*
X629637Y-295949D01*
X629201Y-293616D01*
Y-291282D01*
X629637Y-288949D01*
X630511Y-286907D01*
X631821Y-285158D01*
X633349Y-283991D01*
X635096Y-283699D01*
X636842Y-283991D01*
X638371Y-285158D01*
X639681Y-286907D01*
X640555Y-288949D01*
X640991Y-291282D01*
Y-293616D01*
X640555Y-295949D01*
X639681Y-297991D01*
X638371Y-299741D01*
X636842Y-300907D01*
X635096Y-301199D01*
G01X685937Y-283699D02*
X691396Y-301199D01*
X696855Y-283699D01*
G01X713263Y-301199D02*
X704529D01*
Y-283699D01*
X713263D01*
G01X709769Y-292157D02*
X704529D01*
G01X722029Y-301199D02*
Y-283699D01*
X727488D01*
X729234Y-284574D01*
X730326Y-285741D01*
X730763Y-288074D01*
X730326Y-290408D01*
X729016Y-291866D01*
X727488Y-292741D01*
X722029D01*
G01X727488D02*
X730763Y-301199D01*
G01X743896Y-301782D02*
X743459Y-301491D01*
Y-300907D01*
X743896Y-300616D01*
X744333Y-300907D01*
Y-301491D01*
X743896Y-301782D01*
G01X717646Y-346199D02*
Y-328699D01*
X715026Y-332199D01*
G01Y-346199D02*
X720266D01*
G01X819479Y-328699D02*
Y-346199D01*
X828213D01*
G01X843966D02*
Y-328699D01*
X835887Y-341241D01*
X846805D01*
G01X853387Y-328699D02*
X858846Y-346199D01*
X864305Y-328699D01*
G01X881149Y-330158D02*
X879839Y-329282D01*
X878311Y-328699D01*
X876564D01*
X874599Y-329574D01*
X873071Y-331032D01*
X871979Y-332783D01*
X871106Y-335699D01*
X870887Y-338324D01*
X871324Y-340949D01*
X871979Y-342699D01*
X873289Y-344449D01*
X874818Y-345616D01*
X876346Y-346199D01*
X877874D01*
X879403Y-345616D01*
X880713Y-344741D01*
X881805Y-343575D01*
G01X898649Y-330158D02*
X897339Y-329282D01*
X895811Y-328699D01*
X894064D01*
X892099Y-329574D01*
X890571Y-331032D01*
X889479Y-332783D01*
X888606Y-335699D01*
X888387Y-338324D01*
X888824Y-340949D01*
X889479Y-342699D01*
X890789Y-344449D01*
X892318Y-345616D01*
X893846Y-346199D01*
X895374D01*
X896903Y-345616D01*
X898213Y-344741D01*
X899305Y-343575D01*
G01X819479Y-283699D02*
Y-301199D01*
X828213D01*
G01X845276D02*
Y-289533D01*
G01Y-291574D02*
X844403Y-290408D01*
X843092Y-289824D01*
X841564Y-289533D01*
X840036Y-290116D01*
X838726Y-291282D01*
X837852Y-293032D01*
X837416Y-295366D01*
X837852Y-297699D01*
X838726Y-299449D01*
X840036Y-300616D01*
X841564Y-301199D01*
X843092Y-300907D01*
X844403Y-300033D01*
X845276Y-298866D01*
G01X854261Y-306449D02*
X855571Y-307032D01*
X857318Y-306449D01*
X858409Y-305283D01*
X859283Y-303824D01*
X860592Y-299158D01*
X863431Y-289533D01*
G01X856444D02*
X860592Y-299158D01*
G01X873071Y-293324D02*
X880058D01*
X879403Y-291282D01*
X878311Y-290116D01*
X876783Y-289533D01*
X875254Y-289824D01*
X873944Y-290699D01*
X873071Y-292741D01*
X872634Y-294491D01*
Y-296241D01*
X873071Y-297991D01*
X874163Y-299741D01*
X875473Y-300907D01*
X877001Y-301199D01*
X878529Y-300616D01*
X880058Y-298866D01*
G01X890789Y-301199D02*
Y-289533D01*
G01Y-291866D02*
X891881Y-290699D01*
X892973Y-289824D01*
X894501Y-289533D01*
X895592Y-289824D01*
X896903Y-290699D01*
G01X959846Y-328699D02*
X962902Y-346199D01*
X966396Y-328699D01*
X969889Y-346199D01*
X972946Y-328699D01*
G01X979529Y-346199D02*
Y-328699D01*
X984769D01*
X986516Y-329574D01*
X987826Y-331616D01*
X988263Y-333949D01*
X987826Y-336282D01*
X986734Y-338032D01*
X984769Y-338908D01*
X979529D01*
G01X996811Y-346199D02*
Y-328699D01*
G01X1005981D02*
Y-346199D01*
G01Y-337449D02*
X996811D01*
G01X1016058Y-340366D02*
X1021734D01*
G01X1031593Y-346199D02*
Y-328699D01*
G01X1039889D02*
X1031593Y-339491D01*
G01X1041199Y-346199D02*
X1035304Y-334533D01*
G01X1058263Y-346199D02*
X1049529D01*
Y-328699D01*
X1058263D01*
G01X1054769Y-337157D02*
X1049529D01*
G01X1066374Y-346199D02*
Y-328699D01*
X1076418Y-346199D01*
Y-328699D01*
G01X1083874Y-346199D02*
Y-328699D01*
X1093918Y-346199D01*
Y-328699D01*
G01X961593Y-301199D02*
Y-283699D01*
X965959D01*
X967706Y-284574D01*
X969016Y-285741D01*
X970108Y-287490D01*
X970981Y-289533D01*
X971199Y-292449D01*
X970981Y-295366D01*
X970108Y-297408D01*
X969016Y-299158D01*
X967706Y-300324D01*
X965959Y-301199D01*
X961593D01*
G01X980621Y-293324D02*
X987608D01*
X986953Y-291282D01*
X985861Y-290116D01*
X984333Y-289533D01*
X982804Y-289824D01*
X981494Y-290699D01*
X980621Y-292741D01*
X980184Y-294491D01*
Y-296241D01*
X980621Y-297991D01*
X981713Y-299741D01*
X983023Y-300907D01*
X984551Y-301199D01*
X986079Y-300616D01*
X987608Y-298866D01*
G01X998121Y-299158D02*
X999213Y-300324D01*
X1000741Y-301199D01*
X1002051D01*
X1003361Y-300616D01*
X1004234Y-299741D01*
X1004671Y-298575D01*
X1004453Y-296824D01*
X1003579Y-295949D01*
X999649Y-294199D01*
X998776Y-292157D01*
X999213Y-290699D01*
X1000086Y-289824D01*
X1001396Y-289533D01*
X1002706Y-289824D01*
X1004016Y-290699D01*
G01X1018896Y-289533D02*
Y-301199D01*
G01Y-284866D02*
X1018459Y-284574D01*
Y-283991D01*
X1018896Y-283699D01*
X1019333Y-283991D01*
Y-284574D01*
X1018896Y-284866D01*
G01X1033339Y-305574D02*
X1034868Y-306741D01*
X1036614Y-307032D01*
X1038142Y-306741D01*
X1039453Y-305283D01*
X1040326Y-303241D01*
Y-289533D01*
G01Y-291866D02*
X1039453Y-290699D01*
X1038142Y-289824D01*
X1036614Y-289533D01*
X1034868Y-290116D01*
X1033776Y-291282D01*
X1032902Y-293324D01*
X1032466Y-295366D01*
X1032684Y-297116D01*
X1033558Y-299158D01*
X1034868Y-300616D01*
X1036614Y-301199D01*
X1037924Y-300907D01*
X1039453Y-299741D01*
X1040326Y-298575D01*
G01X1050184Y-301199D02*
Y-289533D01*
G01Y-292449D02*
X1051058Y-290991D01*
X1052368Y-289824D01*
X1054114Y-289533D01*
X1055642Y-289824D01*
X1056953Y-290991D01*
X1057608Y-293032D01*
Y-301199D01*
G01X1068121Y-293324D02*
X1075108D01*
X1074453Y-291282D01*
X1073361Y-290116D01*
X1071833Y-289533D01*
X1070304Y-289824D01*
X1068994Y-290699D01*
X1068121Y-292741D01*
X1067684Y-294491D01*
Y-296241D01*
X1068121Y-297991D01*
X1069213Y-299741D01*
X1070523Y-300907D01*
X1072051Y-301199D01*
X1073579Y-300616D01*
X1075108Y-298866D01*
G01X1085839Y-301199D02*
Y-289533D01*
G01Y-291866D02*
X1086931Y-290699D01*
X1088023Y-289824D01*
X1089551Y-289533D01*
X1090642Y-289824D01*
X1091953Y-290699D01*
G01X1132596Y-346199D02*
Y-328699D01*
X1129976Y-332199D01*
G01Y-346199D02*
X1135216D01*
G01X1150096D02*
Y-328699D01*
X1147476Y-332199D01*
G01Y-346199D02*
X1152716D01*
G01X1163666Y-346782D02*
X1171526Y-328699D01*
G01X1185096Y-346199D02*
Y-328699D01*
X1182476Y-332199D01*
G01Y-346199D02*
X1187716D01*
G01X1198448Y-338908D02*
X1199976Y-336866D01*
X1201286Y-335699D01*
X1203033Y-335116D01*
X1204561Y-335699D01*
X1205653Y-336866D01*
X1206526Y-338616D01*
X1206744Y-340657D01*
X1206526Y-342408D01*
X1205653Y-344158D01*
X1204342Y-345616D01*
X1202814Y-346199D01*
X1201068Y-345616D01*
X1199539Y-343866D01*
X1198666Y-341241D01*
X1198448Y-338324D01*
X1198884Y-334533D01*
X1199539Y-332490D01*
X1200631Y-330449D01*
X1202159Y-328991D01*
X1203688Y-328699D01*
X1205216Y-329282D01*
X1206308Y-330741D01*
G01X1216166Y-346782D02*
X1224026Y-328699D01*
G01X1233448Y-331616D02*
X1234758Y-329866D01*
X1236286Y-328991D01*
X1238033Y-328699D01*
X1240216Y-329282D01*
X1241744Y-330741D01*
X1242181Y-332490D01*
X1241963Y-334241D01*
X1241089Y-335699D01*
X1236723Y-338616D01*
X1234758Y-340657D01*
X1233448Y-343575D01*
X1233011Y-346199D01*
X1242181D01*
G01X1255096Y-328699D02*
X1253349Y-329282D01*
X1252039Y-330741D01*
X1251166Y-332490D01*
X1250511Y-334824D01*
X1250293Y-337449D01*
X1250511Y-340074D01*
X1251166Y-342408D01*
X1252039Y-344158D01*
X1253349Y-345616D01*
X1255096Y-346199D01*
X1256842Y-345616D01*
X1258153Y-344158D01*
X1259026Y-342408D01*
X1259681Y-340074D01*
X1259899Y-337449D01*
X1259681Y-334824D01*
X1259026Y-332490D01*
X1258153Y-330741D01*
X1256842Y-329282D01*
X1255096Y-328699D01*
G01X1272596Y-346199D02*
Y-328699D01*
X1269976Y-332199D01*
G01Y-346199D02*
X1275216D01*
G01X1285948Y-338908D02*
X1287476Y-336866D01*
X1288786Y-335699D01*
X1290533Y-335116D01*
X1292061Y-335699D01*
X1293153Y-336866D01*
X1294026Y-338616D01*
X1294244Y-340657D01*
X1294026Y-342408D01*
X1293153Y-344158D01*
X1291842Y-345616D01*
X1290314Y-346199D01*
X1288568Y-345616D01*
X1287039Y-343866D01*
X1286166Y-341241D01*
X1285948Y-338324D01*
X1286384Y-334533D01*
X1287039Y-332490D01*
X1288131Y-330449D01*
X1289659Y-328991D01*
X1291188Y-328699D01*
X1292716Y-329282D01*
X1293808Y-330741D01*
G01X1180293Y-301199D02*
Y-283699D01*
X1184659D01*
X1186406Y-284574D01*
X1187716Y-285741D01*
X1188808Y-287490D01*
X1189681Y-289533D01*
X1189899Y-292449D01*
X1189681Y-295366D01*
X1188808Y-297408D01*
X1187716Y-299158D01*
X1186406Y-300324D01*
X1184659Y-301199D01*
X1180293D01*
G01X1206526D02*
Y-289533D01*
G01Y-291574D02*
X1205653Y-290408D01*
X1204342Y-289824D01*
X1202814Y-289533D01*
X1201286Y-290116D01*
X1199976Y-291282D01*
X1199102Y-293032D01*
X1198666Y-295366D01*
X1199102Y-297699D01*
X1199976Y-299449D01*
X1201286Y-300616D01*
X1202814Y-301199D01*
X1204342Y-300907D01*
X1205653Y-300033D01*
X1206526Y-298866D01*
G01X1220096Y-283699D02*
Y-301199D01*
G01X1217039Y-289533D02*
X1223153D01*
G01X1234321Y-293324D02*
X1241308D01*
X1240653Y-291282D01*
X1239561Y-290116D01*
X1238033Y-289533D01*
X1236504Y-289824D01*
X1235194Y-290699D01*
X1234321Y-292741D01*
X1233884Y-294491D01*
Y-296241D01*
X1234321Y-297991D01*
X1235413Y-299741D01*
X1236723Y-300907D01*
X1238251Y-301199D01*
X1239779Y-300616D01*
X1241308Y-298866D01*
G54D39*
G01X127746Y-260199D02*
X95746D01*
G01X127746Y-276199D02*
Y-356199D01*
G01D02*
X1310146D01*
G01X127746Y-311699D02*
X1310146D01*
G01X123746Y-260199D02*
G02I-12000J0D01*
G01X118596D02*
G02I-6850J0D01*
G01X111746Y-276199D02*
Y-244199D01*
G01X127746Y-276199D02*
X1310146D01*
G01X522646D02*
Y-356199D01*
G01X660146Y-276199D02*
Y-356199D01*
G01X775146Y-276199D02*
Y-356199D01*
G01X942646Y-276199D02*
Y-356199D01*
G01X1112646Y-276199D02*
Y-356199D01*
G01X1310146Y-276199D02*
Y-356199D01*
G01X1342146Y-260199D02*
X1310146D01*
G01X1338146D02*
G02I-12000J0D01*
G01X1332996D02*
G02I-6850J0D01*
G01X1326146Y-276199D02*
Y-244199D01*
M02*
